%FSTAX25Y25*%
%MOIN*%
%SFA1B1*%

%IPPOS*%
%ADD10C,0.008000*%
%ADD11C,0.009840*%
%ADD12C,0.023620*%
%ADD13C,0.003940*%
%ADD14C,0.010000*%
%ADD15C,0.007870*%
%ADD16C,0.015750*%
%ADD17C,0.015750*%
%ADD18C,0.006000*%
%ADD19C,0.004720*%
%ADD20C,0.007000*%
%ADD21C,0.005910*%
%ADD22C,0.005000*%
%ADD23C,0.007990*%
%ADD24C,0.009000*%
%ADD25R,0.025000X0.010000*%
%LNgrandmaster-1*%
%LPD*%
G54D10*
X0643265Y05373D02*
D01*
X0643229Y0538329*
X0643121Y0539354*
X0642942Y0540369*
X0642693Y0541369*
X0642374Y0542349*
X0641988Y0543305*
X0641536Y0544231*
X0641021Y0545124*
X0640445Y0545978*
X063981Y054679*
X0639121Y0547556*
X0638379Y0548272*
X063759Y0548934*
X0636756Y054954*
X0635882Y0550086*
X0634972Y055057*
X0634031Y0550989*
X0633062Y0551342*
X0632071Y0551626*
X0631063Y055184*
X0630043Y0551984*
X0629015Y0552056*
X0627984*
X0626956Y0551984*
X0625936Y055184*
X0624928Y0551626*
X0623937Y0551342*
X0622968Y0550989*
X0622027Y055057*
X0621117Y0550086*
X0620243Y054954*
X0619409Y0548934*
X061862Y0548272*
X0617878Y0547556*
X0617189Y054679*
X0616554Y0545978*
X0615978Y0545124*
X0615463Y0544231*
X0615011Y0543305*
X0614625Y0542349*
X0614306Y0541369*
X0614057Y0540369*
X0613878Y0539354*
X061377Y0538329*
X0613735Y05373*
X061377Y053627*
X0613878Y0535245*
X0614057Y053423*
X0614306Y053323*
X0614625Y053225*
X0615011Y0531294*
X0615463Y0530368*
X0615978Y0529475*
X0616554Y0528621*
X0617189Y0527809*
X0617878Y0527043*
X061862Y0526327*
X0619409Y0525665*
X0620243Y0525059*
X0621117Y0524513*
X0622027Y0524029*
X0622968Y052361*
X0623937Y0523257*
X0624928Y0522973*
X0625936Y0522759*
X0626956Y0522615*
X0627984Y0522543*
X0629015*
X0630043Y0522615*
X0631063Y0522759*
X0632071Y0522973*
X0633062Y0523257*
X0634031Y052361*
X0634972Y0524029*
X0635882Y0524513*
X0636756Y0525059*
X063759Y0525665*
X0638379Y0526327*
X0639121Y0527043*
X063981Y0527809*
X0640445Y0528621*
X0641021Y0529475*
X0641536Y0530368*
X0641988Y0531294*
X0642374Y053225*
X0642693Y053323*
X0642942Y053423*
X0643121Y0535245*
X0643229Y053627*
X0643265Y05373*
X1335365Y05701D02*
D01*
X1335329Y0571129*
X1335221Y0572154*
X1335042Y0573169*
X1334793Y0574169*
X1334474Y0575149*
X1334088Y0576105*
X1333636Y0577031*
X1333121Y0577924*
X1332545Y0578778*
X133191Y057959*
X1331221Y0580356*
X1330479Y0581072*
X132969Y0581734*
X1328856Y058234*
X1327982Y0582886*
X1327072Y058337*
X1326131Y0583789*
X1325162Y0584142*
X1324171Y0584426*
X1323163Y058464*
X1322143Y0584784*
X1321115Y0584856*
X1320084*
X1319056Y0584784*
X1318036Y058464*
X1317028Y0584426*
X1316037Y0584142*
X1315068Y0583789*
X1314127Y058337*
X1313217Y0582886*
X1312343Y058234*
X1311509Y0581734*
X131072Y0581072*
X1309978Y0580356*
X1309289Y057959*
X1308654Y0578778*
X1308078Y0577924*
X1307563Y0577031*
X1307111Y0576105*
X1306725Y0575149*
X1306406Y0574169*
X1306157Y0573169*
X1305978Y0572154*
X130587Y0571129*
X1305835Y05701*
X130587Y056907*
X1305978Y0568045*
X1306157Y056703*
X1306406Y056603*
X1306725Y056505*
X1307111Y0564094*
X1307563Y0563168*
X1308078Y0562275*
X1308654Y0561421*
X1309289Y0560609*
X1309978Y0559843*
X131072Y0559127*
X1311509Y0558465*
X1312343Y0557859*
X1313217Y0557313*
X1314127Y0556829*
X1315068Y055641*
X1316037Y0556057*
X1317028Y0555773*
X1318036Y0555559*
X1319056Y0555415*
X1320084Y0555343*
X1321115*
X1322143Y0555415*
X1323163Y0555559*
X1324171Y0555773*
X1325162Y0556057*
X1326131Y055641*
X1327072Y0556829*
X1327982Y0557313*
X1328856Y0557859*
X132969Y0558465*
X1330479Y0559127*
X1331221Y0559843*
X133191Y0560609*
X1332545Y0561421*
X1333121Y0562275*
X1333636Y0563168*
X1334088Y0564094*
X1334474Y056505*
X1334793Y056603*
X1335042Y056703*
X1335221Y0568045*
X1335329Y056907*
X1335365Y05701*
X0644165Y09156D02*
D01*
X0644129Y0916629*
X0644021Y0917654*
X0643842Y0918669*
X0643593Y0919669*
X0643274Y0920649*
X0642888Y0921605*
X0642436Y0922531*
X0641921Y0923424*
X0641345Y0924278*
X064071Y092509*
X0640021Y0925856*
X0639279Y0926572*
X063849Y0927234*
X0637656Y092784*
X0636782Y0928386*
X0635872Y092887*
X0634931Y0929289*
X0633962Y0929642*
X0632971Y0929926*
X0631963Y093014*
X0630943Y0930284*
X0629915Y0930356*
X0628884*
X0627856Y0930284*
X0626836Y093014*
X0625828Y0929926*
X0624837Y0929642*
X0623868Y0929289*
X0622927Y092887*
X0622017Y0928386*
X0621143Y092784*
X0620309Y0927234*
X061952Y0926572*
X0618778Y0925856*
X0618089Y092509*
X0617454Y0924278*
X0616878Y0923424*
X0616363Y0922531*
X0615911Y0921605*
X0615525Y0920649*
X0615206Y0919669*
X0614957Y0918669*
X0614778Y0917654*
X061467Y0916629*
X0614635Y09156*
X061467Y091457*
X0614778Y0913545*
X0614957Y091253*
X0615206Y091153*
X0615525Y091055*
X0615911Y0909594*
X0616363Y0908668*
X0616878Y0907775*
X0617454Y0906921*
X0618089Y0906109*
X0618778Y0905343*
X061952Y0904627*
X0620309Y0903965*
X0621143Y0903359*
X0622017Y0902813*
X0622927Y0902329*
X0623868Y090191*
X0624837Y0901557*
X0625828Y0901273*
X0626836Y0901059*
X0627856Y0900915*
X0628884Y0900843*
X0629915*
X0630943Y0900915*
X0631963Y0901059*
X0632971Y0901273*
X0633962Y0901557*
X0634931Y090191*
X0635872Y0902329*
X0636782Y0902813*
X0637656Y0903359*
X063849Y0903965*
X0639279Y0904627*
X0640021Y0905343*
X064071Y0906109*
X0641345Y0906921*
X0641921Y0907775*
X0642436Y0908668*
X0642888Y0909594*
X0643274Y091055*
X0643593Y091153*
X0643842Y091253*
X0644021Y0913545*
X0644129Y091457*
X0644165Y09156*
X1335365Y09168D02*
D01*
X1335329Y0917829*
X1335221Y0918854*
X1335042Y0919869*
X1334793Y0920869*
X1334474Y0921849*
X1334088Y0922805*
X1333636Y0923731*
X1333121Y0924624*
X1332545Y0925478*
X133191Y092629*
X1331221Y0927056*
X1330479Y0927772*
X132969Y0928434*
X1328856Y092904*
X1327982Y0929586*
X1327072Y093007*
X1326131Y0930489*
X1325162Y0930842*
X1324171Y0931126*
X1323163Y093134*
X1322143Y0931484*
X1321115Y0931556*
X1320084*
X1319056Y0931484*
X1318036Y093134*
X1317028Y0931126*
X1316037Y0930842*
X1315068Y0930489*
X1314127Y093007*
X1313217Y0929586*
X1312343Y092904*
X1311509Y0928434*
X131072Y0927772*
X1309978Y0927056*
X1309289Y092629*
X1308654Y0925478*
X1308078Y0924624*
X1307563Y0923731*
X1307111Y0922805*
X1306725Y0921849*
X1306406Y0920869*
X1306157Y0919869*
X1305978Y0918854*
X130587Y0917829*
X1305835Y09168*
X130587Y091577*
X1305978Y0914745*
X1306157Y091373*
X1306406Y091273*
X1306725Y091175*
X1307111Y0910794*
X1307563Y0909868*
X1308078Y0908975*
X1308654Y0908121*
X1309289Y0907309*
X1309978Y0906543*
X131072Y0905827*
X1311509Y0905165*
X1312343Y0904559*
X1313217Y0904013*
X1314127Y0903529*
X1315068Y090311*
X1316037Y0902757*
X1317028Y0902473*
X1318036Y0902259*
X1319056Y0902115*
X1320084Y0902043*
X1321115*
X1322143Y0902115*
X1323163Y0902259*
X1324171Y0902473*
X1325162Y0902757*
X1326131Y090311*
X1327072Y0903529*
X1327982Y0904013*
X1328856Y0904559*
X132969Y0905165*
X1330479Y0905827*
X1331221Y0906543*
X133191Y0907309*
X1332545Y0908121*
X1333121Y0908975*
X1333636Y0909868*
X1334088Y0910794*
X1334474Y091175*
X1334793Y091273*
X1335042Y091373*
X1335221Y0914745*
X1335329Y091577*
X1335365Y09168*
X0926421Y0816685D02*
X0930358D01*
X0949863Y0844244D02*
X0961854D01*
Y0833069D02*
Y0844244D01*
Y0816685D02*
Y0820622D01*
X0957917Y0816685D02*
X0961854D01*
X0926421D02*
Y0820622D01*
Y0840307D02*
Y0844244D01*
X0930358*
X09395Y07856D02*
Y07876D01*
Y07856D02*
X09415D01*
X09535D02*
X09555D01*
Y07876*
Y08076D02*
Y08096D01*
X09535D02*
X09555D01*
X09395D02*
X0944895D01*
X09395Y0803325D02*
Y08096D01*
X10925Y09155D02*
Y09165D01*
Y09155D02*
X11105D01*
Y09165*
Y09255D02*
Y09265D01*
X10925D02*
X11105D01*
X10925Y09255D02*
Y09265D01*
X119Y0920961D02*
X123D01*
Y0879622D02*
Y0920961D01*
X119Y0879622D02*
Y088415D01*
X1221433Y0879622D02*
X123D01*
X119Y0904228D02*
Y0920961D01*
Y0879622D02*
X1200961D01*
X129937Y0857604D02*
Y0936088D01*
X1243465Y0853347D02*
X129937D01*
X1243465D02*
Y0936088D01*
X104Y09155D02*
Y09165D01*
Y09155D02*
X1058D01*
Y09165*
Y09255D02*
Y09265D01*
X104D02*
X1058D01*
X104Y09255D02*
Y09265D01*
G54D11*
X0952201Y0875429D02*
D01*
X0952199Y0875463*
X0952196Y0875497*
X095219Y0875531*
X0952181Y0875564*
X0952171Y0875597*
X0952158Y0875629*
X0952143Y0875659*
X0952126Y0875689*
X0952107Y0875718*
X0952085Y0875745*
X0952062Y087577*
X0952038Y0875794*
X0952011Y0875816*
X0951984Y0875836*
X0951955Y0875855*
X0951924Y0875871*
X0951893Y0875885*
X0951861Y0875896*
X0951828Y0875906*
X0951794Y0875913*
X095176Y0875918*
X0951726Y087592*
X0951691*
X0951657Y0875918*
X0951623Y0875913*
X0951589Y0875906*
X0951556Y0875896*
X0951524Y0875885*
X0951493Y0875871*
X0951463Y0875855*
X0951433Y0875836*
X0951406Y0875816*
X0951379Y0875794*
X0951355Y087577*
X0951332Y0875745*
X095131Y0875718*
X0951291Y0875689*
X0951274Y0875659*
X0951259Y0875629*
X0951246Y0875597*
X0951236Y0875564*
X0951227Y0875531*
X0951221Y0875497*
X0951218Y0875463*
X0951217Y0875429*
X0951218Y0875394*
X0951221Y087536*
X0951227Y0875326*
X0951236Y0875293*
X0951246Y087526*
X0951259Y0875228*
X0951274Y0875198*
X0951291Y0875168*
X095131Y0875139*
X0951332Y0875112*
X0951355Y0875087*
X0951379Y0875063*
X0951406Y0875041*
X0951433Y0875021*
X0951463Y0875002*
X0951493Y0874986*
X0951524Y0874972*
X0951556Y0874961*
X0951589Y0874951*
X0951623Y0874944*
X0951657Y0874939*
X0951691Y0874937*
X0951726*
X095176Y0874939*
X0951794Y0874944*
X0951828Y0874951*
X0951861Y0874961*
X0951893Y0874972*
X0951924Y0874986*
X0951955Y0875002*
X0951984Y0875021*
X0952011Y0875041*
X0952038Y0875063*
X0952062Y0875087*
X0952085Y0875112*
X0952107Y0875139*
X0952126Y0875168*
X0952143Y0875198*
X0952158Y0875228*
X0952171Y087526*
X0952181Y0875293*
X095219Y0875326*
X0952196Y087536*
X0952199Y0875394*
X0952201Y0875429*
X0762664Y0923401D02*
D01*
X0762662Y0923435*
X0762659Y0923469*
X0762653Y0923503*
X0762644Y0923536*
X0762634Y0923569*
X0762621Y0923601*
X0762606Y0923631*
X0762589Y0923661*
X076257Y092369*
X0762548Y0923717*
X0762525Y0923742*
X0762501Y0923766*
X0762474Y0923788*
X0762447Y0923808*
X0762418Y0923827*
X0762387Y0923843*
X0762356Y0923857*
X0762324Y0923868*
X0762291Y0923878*
X0762257Y0923885*
X0762223Y092389*
X0762189Y0923892*
X0762154*
X076212Y092389*
X0762086Y0923885*
X0762052Y0923878*
X0762019Y0923868*
X0761987Y0923857*
X0761956Y0923843*
X0761926Y0923827*
X0761896Y0923808*
X0761869Y0923788*
X0761842Y0923766*
X0761818Y0923742*
X0761795Y0923717*
X0761773Y092369*
X0761754Y0923661*
X0761737Y0923631*
X0761722Y0923601*
X0761709Y0923569*
X0761699Y0923536*
X076169Y0923503*
X0761684Y0923469*
X0761681Y0923435*
X076168Y0923401*
X0761681Y0923366*
X0761684Y0923332*
X076169Y0923298*
X0761699Y0923265*
X0761709Y0923232*
X0761722Y09232*
X0761737Y092317*
X0761754Y092314*
X0761773Y0923111*
X0761795Y0923084*
X0761818Y0923059*
X0761842Y0923035*
X0761869Y0923013*
X0761896Y0922993*
X0761926Y0922974*
X0761956Y0922958*
X0761987Y0922944*
X0762019Y0922933*
X0762052Y0922923*
X0762086Y0922916*
X076212Y0922911*
X0762154Y0922909*
X0762189*
X0762223Y0922911*
X0762257Y0922916*
X0762291Y0922923*
X0762324Y0922933*
X0762356Y0922944*
X0762387Y0922958*
X0762418Y0922974*
X0762447Y0922993*
X0762474Y0923013*
X0762501Y0923035*
X0762525Y0923059*
X0762548Y0923084*
X076257Y0923111*
X0762589Y092314*
X0762606Y092317*
X0762621Y09232*
X0762634Y0923232*
X0762644Y0923265*
X0762653Y0923298*
X0762659Y0923332*
X0762662Y0923366*
X0762664Y0923401*
X0874016Y082339D02*
D01*
X0874014Y0823424*
X0874011Y0823458*
X0874005Y0823492*
X0873996Y0823525*
X0873986Y0823558*
X0873973Y082359*
X0873958Y082362*
X0873941Y082365*
X0873922Y0823679*
X08739Y0823706*
X0873877Y0823731*
X0873853Y0823755*
X0873826Y0823777*
X0873799Y0823797*
X087377Y0823816*
X0873739Y0823832*
X0873708Y0823846*
X0873676Y0823857*
X0873643Y0823867*
X0873609Y0823874*
X0873575Y0823879*
X0873541Y0823881*
X0873506*
X0873472Y0823879*
X0873438Y0823874*
X0873404Y0823867*
X0873371Y0823857*
X0873339Y0823846*
X0873308Y0823832*
X0873278Y0823816*
X0873248Y0823797*
X0873221Y0823777*
X0873194Y0823755*
X087317Y0823731*
X0873147Y0823706*
X0873125Y0823679*
X0873106Y082365*
X0873089Y082362*
X0873074Y082359*
X0873061Y0823558*
X0873051Y0823525*
X0873042Y0823492*
X0873036Y0823458*
X0873033Y0823424*
X0873032Y082339*
X0873033Y0823355*
X0873036Y0823321*
X0873042Y0823287*
X0873051Y0823254*
X0873061Y0823221*
X0873074Y0823189*
X0873089Y0823159*
X0873106Y0823129*
X0873125Y08231*
X0873147Y0823073*
X087317Y0823048*
X0873194Y0823024*
X0873221Y0823002*
X0873248Y0822982*
X0873278Y0822963*
X0873308Y0822947*
X0873339Y0822933*
X0873371Y0822922*
X0873404Y0822912*
X0873438Y0822905*
X0873472Y08229*
X0873506Y0822898*
X0873541*
X0873575Y08229*
X0873609Y0822905*
X0873643Y0822912*
X0873676Y0822922*
X0873708Y0822933*
X0873739Y0822947*
X087377Y0822963*
X0873799Y0822982*
X0873826Y0823002*
X0873853Y0823024*
X0873877Y0823048*
X08739Y0823073*
X0873922Y08231*
X0873941Y0823129*
X0873958Y0823159*
X0873973Y0823189*
X0873986Y0823221*
X0873996Y0823254*
X0874005Y0823287*
X0874011Y0823321*
X0874014Y0823355*
X0874016Y082339*
X0720724Y0582634D02*
D01*
X0720722Y0582668*
X0720719Y0582702*
X0720713Y0582736*
X0720704Y0582769*
X0720694Y0582802*
X0720681Y0582834*
X0720666Y0582864*
X0720649Y0582894*
X072063Y0582923*
X0720608Y058295*
X0720585Y0582975*
X0720561Y0582999*
X0720534Y0583021*
X0720507Y0583041*
X0720478Y058306*
X0720447Y0583076*
X0720416Y058309*
X0720384Y0583101*
X0720351Y0583111*
X0720317Y0583118*
X0720283Y0583123*
X0720249Y0583125*
X0720214*
X072018Y0583123*
X0720146Y0583118*
X0720112Y0583111*
X0720079Y0583101*
X0720047Y058309*
X0720016Y0583076*
X0719986Y058306*
X0719956Y0583041*
X0719929Y0583021*
X0719902Y0582999*
X0719878Y0582975*
X0719855Y058295*
X0719833Y0582923*
X0719814Y0582894*
X0719797Y0582864*
X0719782Y0582834*
X0719769Y0582802*
X0719759Y0582769*
X071975Y0582736*
X0719744Y0582702*
X0719741Y0582668*
X071974Y0582634*
X0719741Y0582599*
X0719744Y0582565*
X071975Y0582531*
X0719759Y0582498*
X0719769Y0582465*
X0719782Y0582433*
X0719797Y0582403*
X0719814Y0582373*
X0719833Y0582344*
X0719855Y0582317*
X0719878Y0582292*
X0719902Y0582268*
X0719929Y0582246*
X0719956Y0582226*
X0719986Y0582207*
X0720016Y0582191*
X0720047Y0582177*
X0720079Y0582166*
X0720112Y0582156*
X0720146Y0582149*
X072018Y0582144*
X0720214Y0582142*
X0720249*
X0720283Y0582144*
X0720317Y0582149*
X0720351Y0582156*
X0720384Y0582166*
X0720416Y0582177*
X0720447Y0582191*
X0720478Y0582207*
X0720507Y0582226*
X0720534Y0582246*
X0720561Y0582268*
X0720585Y0582292*
X0720608Y0582317*
X072063Y0582344*
X0720649Y0582373*
X0720666Y0582403*
X0720681Y0582433*
X0720694Y0582465*
X0720704Y0582498*
X0720713Y0582531*
X0720719Y0582565*
X0720722Y0582599*
X0720724Y0582634*
X0888701Y0875429D02*
D01*
X0888699Y0875463*
X0888696Y0875497*
X088869Y0875531*
X0888681Y0875564*
X0888671Y0875597*
X0888658Y0875629*
X0888643Y0875659*
X0888626Y0875689*
X0888607Y0875718*
X0888585Y0875745*
X0888562Y087577*
X0888538Y0875794*
X0888511Y0875816*
X0888484Y0875836*
X0888455Y0875855*
X0888424Y0875871*
X0888393Y0875885*
X0888361Y0875896*
X0888328Y0875906*
X0888294Y0875913*
X088826Y0875918*
X0888226Y087592*
X0888191*
X0888157Y0875918*
X0888123Y0875913*
X0888089Y0875906*
X0888056Y0875896*
X0888024Y0875885*
X0887993Y0875871*
X0887963Y0875855*
X0887933Y0875836*
X0887906Y0875816*
X0887879Y0875794*
X0887855Y087577*
X0887832Y0875745*
X088781Y0875718*
X0887791Y0875689*
X0887774Y0875659*
X0887759Y0875629*
X0887746Y0875597*
X0887736Y0875564*
X0887727Y0875531*
X0887721Y0875497*
X0887718Y0875463*
X0887717Y0875429*
X0887718Y0875394*
X0887721Y087536*
X0887727Y0875326*
X0887736Y0875293*
X0887746Y087526*
X0887759Y0875228*
X0887774Y0875198*
X0887791Y0875168*
X088781Y0875139*
X0887832Y0875112*
X0887855Y0875087*
X0887879Y0875063*
X0887906Y0875041*
X0887933Y0875021*
X0887963Y0875002*
X0887993Y0874986*
X0888024Y0874972*
X0888056Y0874961*
X0888089Y0874951*
X0888123Y0874944*
X0888157Y0874939*
X0888191Y0874937*
X0888226*
X088826Y0874939*
X0888294Y0874944*
X0888328Y0874951*
X0888361Y0874961*
X0888393Y0874972*
X0888424Y0874986*
X0888455Y0875002*
X0888484Y0875021*
X0888511Y0875041*
X0888538Y0875063*
X0888562Y0875087*
X0888585Y0875112*
X0888607Y0875139*
X0888626Y0875168*
X0888643Y0875198*
X0888658Y0875228*
X0888671Y087526*
X0888681Y0875293*
X088869Y0875326*
X0888696Y087536*
X0888699Y0875394*
X0888701Y0875429*
X0877201D02*
D01*
X0877199Y0875463*
X0877196Y0875497*
X087719Y0875531*
X0877181Y0875564*
X0877171Y0875597*
X0877158Y0875629*
X0877143Y0875659*
X0877126Y0875689*
X0877107Y0875718*
X0877085Y0875745*
X0877062Y087577*
X0877038Y0875794*
X0877011Y0875816*
X0876984Y0875836*
X0876955Y0875855*
X0876924Y0875871*
X0876893Y0875885*
X0876861Y0875896*
X0876828Y0875906*
X0876794Y0875913*
X087676Y0875918*
X0876726Y087592*
X0876691*
X0876657Y0875918*
X0876623Y0875913*
X0876589Y0875906*
X0876556Y0875896*
X0876524Y0875885*
X0876493Y0875871*
X0876463Y0875855*
X0876433Y0875836*
X0876406Y0875816*
X0876379Y0875794*
X0876355Y087577*
X0876332Y0875745*
X087631Y0875718*
X0876291Y0875689*
X0876274Y0875659*
X0876259Y0875629*
X0876246Y0875597*
X0876236Y0875564*
X0876227Y0875531*
X0876221Y0875497*
X0876218Y0875463*
X0876217Y0875429*
X0876218Y0875394*
X0876221Y087536*
X0876227Y0875326*
X0876236Y0875293*
X0876246Y087526*
X0876259Y0875228*
X0876274Y0875198*
X0876291Y0875168*
X087631Y0875139*
X0876332Y0875112*
X0876355Y0875087*
X0876379Y0875063*
X0876406Y0875041*
X0876433Y0875021*
X0876463Y0875002*
X0876493Y0874986*
X0876524Y0874972*
X0876556Y0874961*
X0876589Y0874951*
X0876623Y0874944*
X0876657Y0874939*
X0876691Y0874937*
X0876726*
X087676Y0874939*
X0876794Y0874944*
X0876828Y0874951*
X0876861Y0874961*
X0876893Y0874972*
X0876924Y0874986*
X0876955Y0875002*
X0876984Y0875021*
X0877011Y0875041*
X0877038Y0875063*
X0877062Y0875087*
X0877085Y0875112*
X0877107Y0875139*
X0877126Y0875168*
X0877143Y0875198*
X0877158Y0875228*
X0877171Y087526*
X0877181Y0875293*
X087719Y0875326*
X0877196Y087536*
X0877199Y0875394*
X0877201Y0875429*
X0929701D02*
D01*
X0929699Y0875463*
X0929696Y0875497*
X092969Y0875531*
X0929681Y0875564*
X0929671Y0875597*
X0929658Y0875629*
X0929643Y0875659*
X0929626Y0875689*
X0929607Y0875718*
X0929585Y0875745*
X0929562Y087577*
X0929538Y0875794*
X0929511Y0875816*
X0929484Y0875836*
X0929455Y0875855*
X0929424Y0875871*
X0929393Y0875885*
X0929361Y0875896*
X0929328Y0875906*
X0929294Y0875913*
X092926Y0875918*
X0929226Y087592*
X0929191*
X0929157Y0875918*
X0929123Y0875913*
X0929089Y0875906*
X0929056Y0875896*
X0929024Y0875885*
X0928993Y0875871*
X0928963Y0875855*
X0928933Y0875836*
X0928906Y0875816*
X0928879Y0875794*
X0928855Y087577*
X0928832Y0875745*
X092881Y0875718*
X0928791Y0875689*
X0928774Y0875659*
X0928759Y0875629*
X0928746Y0875597*
X0928736Y0875564*
X0928727Y0875531*
X0928721Y0875497*
X0928718Y0875463*
X0928717Y0875429*
X0928718Y0875394*
X0928721Y087536*
X0928727Y0875326*
X0928736Y0875293*
X0928746Y087526*
X0928759Y0875228*
X0928774Y0875198*
X0928791Y0875168*
X092881Y0875139*
X0928832Y0875112*
X0928855Y0875087*
X0928879Y0875063*
X0928906Y0875041*
X0928933Y0875021*
X0928963Y0875002*
X0928993Y0874986*
X0929024Y0874972*
X0929056Y0874961*
X0929089Y0874951*
X0929123Y0874944*
X0929157Y0874939*
X0929191Y0874937*
X0929226*
X092926Y0874939*
X0929294Y0874944*
X0929328Y0874951*
X0929361Y0874961*
X0929393Y0874972*
X0929424Y0874986*
X0929455Y0875002*
X0929484Y0875021*
X0929511Y0875041*
X0929538Y0875063*
X0929562Y0875087*
X0929585Y0875112*
X0929607Y0875139*
X0929626Y0875168*
X0929643Y0875198*
X0929658Y0875228*
X0929671Y087526*
X0929681Y0875293*
X092969Y0875326*
X0929696Y087536*
X0929699Y0875394*
X0929701Y0875429*
X0720724Y0687634D02*
D01*
X0720722Y0687668*
X0720719Y0687702*
X0720713Y0687736*
X0720704Y0687769*
X0720694Y0687802*
X0720681Y0687834*
X0720666Y0687864*
X0720649Y0687894*
X072063Y0687923*
X0720608Y068795*
X0720585Y0687975*
X0720561Y0687999*
X0720534Y0688021*
X0720507Y0688041*
X0720478Y068806*
X0720447Y0688076*
X0720416Y068809*
X0720384Y0688101*
X0720351Y0688111*
X0720317Y0688118*
X0720283Y0688123*
X0720249Y0688125*
X0720214*
X072018Y0688123*
X0720146Y0688118*
X0720112Y0688111*
X0720079Y0688101*
X0720047Y068809*
X0720016Y0688076*
X0719986Y068806*
X0719956Y0688041*
X0719929Y0688021*
X0719902Y0687999*
X0719878Y0687975*
X0719855Y068795*
X0719833Y0687923*
X0719814Y0687894*
X0719797Y0687864*
X0719782Y0687834*
X0719769Y0687802*
X0719759Y0687769*
X071975Y0687736*
X0719744Y0687702*
X0719741Y0687668*
X071974Y0687634*
X0719741Y0687599*
X0719744Y0687565*
X071975Y0687531*
X0719759Y0687498*
X0719769Y0687465*
X0719782Y0687433*
X0719797Y0687403*
X0719814Y0687373*
X0719833Y0687344*
X0719855Y0687317*
X0719878Y0687292*
X0719902Y0687268*
X0719929Y0687246*
X0719956Y0687226*
X0719986Y0687207*
X0720016Y0687191*
X0720047Y0687177*
X0720079Y0687166*
X0720112Y0687156*
X0720146Y0687149*
X072018Y0687144*
X0720214Y0687142*
X0720249*
X0720283Y0687144*
X0720317Y0687149*
X0720351Y0687156*
X0720384Y0687166*
X0720416Y0687177*
X0720447Y0687191*
X0720478Y0687207*
X0720507Y0687226*
X0720534Y0687246*
X0720561Y0687268*
X0720585Y0687292*
X0720608Y0687317*
X072063Y0687344*
X0720649Y0687373*
X0720666Y0687403*
X0720681Y0687433*
X0720694Y0687465*
X0720704Y0687498*
X0720713Y0687531*
X0720719Y0687565*
X0720722Y0687599*
X0720724Y0687634*
Y0740134D02*
D01*
X0720722Y0740168*
X0720719Y0740202*
X0720713Y0740236*
X0720704Y0740269*
X0720694Y0740302*
X0720681Y0740334*
X0720666Y0740364*
X0720649Y0740394*
X072063Y0740423*
X0720608Y074045*
X0720585Y0740475*
X0720561Y0740499*
X0720534Y0740521*
X0720507Y0740541*
X0720478Y074056*
X0720447Y0740576*
X0720416Y074059*
X0720384Y0740601*
X0720351Y0740611*
X0720317Y0740618*
X0720283Y0740623*
X0720249Y0740625*
X0720214*
X072018Y0740623*
X0720146Y0740618*
X0720112Y0740611*
X0720079Y0740601*
X0720047Y074059*
X0720016Y0740576*
X0719986Y074056*
X0719956Y0740541*
X0719929Y0740521*
X0719902Y0740499*
X0719878Y0740475*
X0719855Y074045*
X0719833Y0740423*
X0719814Y0740394*
X0719797Y0740364*
X0719782Y0740334*
X0719769Y0740302*
X0719759Y0740269*
X071975Y0740236*
X0719744Y0740202*
X0719741Y0740168*
X071974Y0740134*
X0719741Y0740099*
X0719744Y0740065*
X071975Y0740031*
X0719759Y0739998*
X0719769Y0739965*
X0719782Y0739933*
X0719797Y0739903*
X0719814Y0739873*
X0719833Y0739844*
X0719855Y0739817*
X0719878Y0739792*
X0719902Y0739768*
X0719929Y0739746*
X0719956Y0739726*
X0719986Y0739707*
X0720016Y0739691*
X0720047Y0739677*
X0720079Y0739666*
X0720112Y0739656*
X0720146Y0739649*
X072018Y0739644*
X0720214Y0739642*
X0720249*
X0720283Y0739644*
X0720317Y0739649*
X0720351Y0739656*
X0720384Y0739666*
X0720416Y0739677*
X0720447Y0739691*
X0720478Y0739707*
X0720507Y0739726*
X0720534Y0739746*
X0720561Y0739768*
X0720585Y0739792*
X0720608Y0739817*
X072063Y0739844*
X0720649Y0739873*
X0720666Y0739903*
X0720681Y0739933*
X0720694Y0739965*
X0720704Y0739998*
X0720713Y0740031*
X0720719Y0740065*
X0720722Y0740099*
X0720724Y0740134*
Y0635134D02*
D01*
X0720722Y0635168*
X0720719Y0635202*
X0720713Y0635236*
X0720704Y0635269*
X0720694Y0635302*
X0720681Y0635334*
X0720666Y0635364*
X0720649Y0635394*
X072063Y0635423*
X0720608Y063545*
X0720585Y0635475*
X0720561Y0635499*
X0720534Y0635521*
X0720507Y0635541*
X0720478Y063556*
X0720447Y0635576*
X0720416Y063559*
X0720384Y0635601*
X0720351Y0635611*
X0720317Y0635618*
X0720283Y0635623*
X0720249Y0635625*
X0720214*
X072018Y0635623*
X0720146Y0635618*
X0720112Y0635611*
X0720079Y0635601*
X0720047Y063559*
X0720016Y0635576*
X0719986Y063556*
X0719956Y0635541*
X0719929Y0635521*
X0719902Y0635499*
X0719878Y0635475*
X0719855Y063545*
X0719833Y0635423*
X0719814Y0635394*
X0719797Y0635364*
X0719782Y0635334*
X0719769Y0635302*
X0719759Y0635269*
X071975Y0635236*
X0719744Y0635202*
X0719741Y0635168*
X071974Y0635134*
X0719741Y0635099*
X0719744Y0635065*
X071975Y0635031*
X0719759Y0634998*
X0719769Y0634965*
X0719782Y0634933*
X0719797Y0634903*
X0719814Y0634873*
X0719833Y0634844*
X0719855Y0634817*
X0719878Y0634792*
X0719902Y0634768*
X0719929Y0634746*
X0719956Y0634726*
X0719986Y0634707*
X0720016Y0634691*
X0720047Y0634677*
X0720079Y0634666*
X0720112Y0634656*
X0720146Y0634649*
X072018Y0634644*
X0720214Y0634642*
X0720249*
X0720283Y0634644*
X0720317Y0634649*
X0720351Y0634656*
X0720384Y0634666*
X0720416Y0634677*
X0720447Y0634691*
X0720478Y0634707*
X0720507Y0634726*
X0720534Y0634746*
X0720561Y0634768*
X0720585Y0634792*
X0720608Y0634817*
X072063Y0634844*
X0720649Y0634873*
X0720666Y0634903*
X0720681Y0634933*
X0720694Y0634965*
X0720704Y0634998*
X0720713Y0635031*
X0720719Y0635065*
X0720722Y0635099*
X0720724Y0635134*
X0976764Y0889301D02*
D01*
X0976762Y0889335*
X0976759Y0889369*
X0976753Y0889403*
X0976744Y0889436*
X0976734Y0889469*
X0976721Y0889501*
X0976706Y0889531*
X0976689Y0889561*
X097667Y088959*
X0976648Y0889617*
X0976625Y0889642*
X0976601Y0889666*
X0976574Y0889688*
X0976547Y0889708*
X0976518Y0889727*
X0976487Y0889743*
X0976456Y0889757*
X0976424Y0889768*
X0976391Y0889778*
X0976357Y0889785*
X0976323Y088979*
X0976289Y0889792*
X0976254*
X097622Y088979*
X0976186Y0889785*
X0976152Y0889778*
X0976119Y0889768*
X0976087Y0889757*
X0976056Y0889743*
X0976026Y0889727*
X0975996Y0889708*
X0975969Y0889688*
X0975942Y0889666*
X0975918Y0889642*
X0975895Y0889617*
X0975873Y088959*
X0975854Y0889561*
X0975837Y0889531*
X0975822Y0889501*
X0975809Y0889469*
X0975799Y0889436*
X097579Y0889403*
X0975784Y0889369*
X0975781Y0889335*
X097578Y0889301*
X0975781Y0889266*
X0975784Y0889232*
X097579Y0889198*
X0975799Y0889165*
X0975809Y0889132*
X0975822Y08891*
X0975837Y088907*
X0975854Y088904*
X0975873Y0889011*
X0975895Y0888984*
X0975918Y0888959*
X0975942Y0888935*
X0975969Y0888913*
X0975996Y0888893*
X0976026Y0888874*
X0976056Y0888858*
X0976087Y0888844*
X0976119Y0888833*
X0976152Y0888823*
X0976186Y0888816*
X097622Y0888811*
X0976254Y0888809*
X0976289*
X0976323Y0888811*
X0976357Y0888816*
X0976391Y0888823*
X0976424Y0888833*
X0976456Y0888844*
X0976487Y0888858*
X0976518Y0888874*
X0976547Y0888893*
X0976574Y0888913*
X0976601Y0888935*
X0976625Y0888959*
X0976648Y0888984*
X097667Y0889011*
X0976689Y088904*
X0976706Y088907*
X0976721Y08891*
X0976734Y0889132*
X0976744Y0889165*
X0976753Y0889198*
X0976759Y0889232*
X0976762Y0889266*
X0976764Y0889301*
G54D12*
X0771719Y0917505D02*
D01*
X0771716Y0917587*
X0771707Y0917669*
X0771693Y091775*
X0771673Y091783*
X0771647Y0917908*
X0771616Y0917985*
X077158Y0918059*
X0771539Y091813*
X0771493Y0918199*
X0771442Y0918264*
X0771387Y0918325*
X0771328Y0918382*
X0771265Y0918435*
X0771198Y0918484*
X0771128Y0918527*
X0771055Y0918566*
X077098Y09186*
X0770902Y0918628*
X0770823Y091865*
X0770743Y0918668*
X0770661Y0918679*
X0770579Y0918685*
X0770496*
X0770414Y0918679*
X0770332Y0918668*
X0770252Y091865*
X0770173Y0918628*
X0770095Y09186*
X077002Y0918566*
X0769947Y0918527*
X0769877Y0918484*
X076981Y0918435*
X0769747Y0918382*
X0769688Y0918325*
X0769633Y0918264*
X0769582Y0918199*
X0769536Y091813*
X0769495Y0918059*
X0769459Y0917985*
X0769428Y0917908*
X0769402Y091783*
X0769382Y091775*
X0769368Y0917669*
X0769359Y0917587*
X0769357Y0917505*
X0769359Y0917422*
X0769368Y091734*
X0769382Y0917259*
X0769402Y0917179*
X0769428Y0917101*
X0769459Y0917024*
X0769495Y091695*
X0769536Y0916879*
X0769582Y091681*
X0769633Y0916745*
X0769688Y0916684*
X0769747Y0916627*
X076981Y0916574*
X0769877Y0916525*
X0769947Y0916482*
X077002Y0916443*
X0770095Y0916409*
X0770173Y0916381*
X0770252Y0916359*
X0770332Y0916341*
X0770414Y091633*
X0770496Y0916324*
X0770579*
X0770661Y091633*
X0770743Y0916341*
X0770823Y0916359*
X0770902Y0916381*
X077098Y0916409*
X0771055Y0916443*
X0771128Y0916482*
X0771198Y0916525*
X0771265Y0916574*
X0771328Y0916627*
X0771387Y0916684*
X0771442Y0916745*
X0771493Y091681*
X0771539Y0916879*
X077158Y091695*
X0771616Y0917024*
X0771647Y0917101*
X0771673Y0917179*
X0771693Y0917259*
X0771707Y091734*
X0771716Y0917422*
X0771719Y0917505*
X0985819Y0883405D02*
D01*
X0985816Y0883487*
X0985807Y0883569*
X0985793Y088365*
X0985773Y088373*
X0985747Y0883808*
X0985716Y0883885*
X098568Y0883959*
X0985639Y088403*
X0985593Y0884099*
X0985542Y0884164*
X0985487Y0884225*
X0985428Y0884282*
X0985365Y0884335*
X0985298Y0884384*
X0985228Y0884427*
X0985155Y0884466*
X098508Y08845*
X0985002Y0884528*
X0984923Y088455*
X0984843Y0884568*
X0984761Y0884579*
X0984679Y0884585*
X0984596*
X0984514Y0884579*
X0984432Y0884568*
X0984352Y088455*
X0984273Y0884528*
X0984195Y08845*
X098412Y0884466*
X0984047Y0884427*
X0983977Y0884384*
X098391Y0884335*
X0983847Y0884282*
X0983788Y0884225*
X0983733Y0884164*
X0983682Y0884099*
X0983636Y088403*
X0983595Y0883959*
X0983559Y0883885*
X0983528Y0883808*
X0983502Y088373*
X0983482Y088365*
X0983468Y0883569*
X0983459Y0883487*
X0983457Y0883405*
X0983459Y0883322*
X0983468Y088324*
X0983482Y0883159*
X0983502Y0883079*
X0983528Y0883001*
X0983559Y0882924*
X0983595Y088285*
X0983636Y0882779*
X0983682Y088271*
X0983733Y0882645*
X0983788Y0882584*
X0983847Y0882527*
X098391Y0882474*
X0983977Y0882425*
X0984047Y0882382*
X098412Y0882343*
X0984195Y0882309*
X0984273Y0882281*
X0984352Y0882259*
X0984432Y0882241*
X0984514Y088223*
X0984596Y0882224*
X0984679*
X0984761Y088223*
X0984843Y0882241*
X0984923Y0882259*
X0985002Y0882281*
X098508Y0882309*
X0985155Y0882343*
X0985228Y0882382*
X0985298Y0882425*
X0985365Y0882474*
X0985428Y0882527*
X0985487Y0882584*
X0985542Y0882645*
X0985593Y088271*
X0985639Y0882779*
X098568Y088285*
X0985716Y0882924*
X0985747Y0883001*
X0985773Y0883079*
X0985793Y0883159*
X0985807Y088324*
X0985816Y0883322*
X0985819Y0883405*
G54D13*
X1218126Y0873748D02*
D01*
X1218125Y0873761*
X1218124Y0873775*
X1218121Y0873788*
X1218118Y0873802*
X1218114Y0873815*
X1218108Y0873828*
X1218102Y087384*
X1218096Y0873852*
X1218088Y0873863*
X1218079Y0873874*
X121807Y0873884*
X121806Y0873894*
X121805Y0873903*
X1218039Y0873911*
X1218027Y0873918*
X1218015Y0873925*
X1218002Y087393*
X1217989Y0873935*
X1217976Y0873939*
X1217963Y0873942*
X1217949Y0873943*
X1217935Y0873944*
X1217922*
X1217908Y0873943*
X1217894Y0873942*
X1217881Y0873939*
X1217868Y0873935*
X1217855Y087393*
X1217842Y0873925*
X121783Y0873918*
X1217818Y0873911*
X1217807Y0873903*
X1217797Y0873894*
X1217787Y0873884*
X1217778Y0873874*
X1217769Y0873863*
X1217761Y0873852*
X1217755Y087384*
X1217749Y0873828*
X1217743Y0873815*
X1217739Y0873802*
X1217736Y0873788*
X1217733Y0873775*
X1217732Y0873761*
X1217732Y0873748*
X1217732Y0873734*
X1217733Y087372*
X1217736Y0873707*
X1217739Y0873693*
X1217743Y087368*
X1217749Y0873667*
X1217755Y0873655*
X1217761Y0873643*
X1217769Y0873632*
X1217778Y0873621*
X1217787Y0873611*
X1217797Y0873601*
X1217807Y0873592*
X1217818Y0873584*
X121783Y0873577*
X1217842Y087357*
X1217855Y0873565*
X1217868Y087356*
X1217881Y0873556*
X1217894Y0873553*
X1217908Y0873552*
X1217922Y0873551*
X1217935*
X1217949Y0873552*
X1217963Y0873553*
X1217976Y0873556*
X1217989Y087356*
X1218002Y0873565*
X1218015Y087357*
X1218027Y0873577*
X1218039Y0873584*
X121805Y0873592*
X121806Y0873601*
X121807Y0873611*
X1218079Y0873621*
X1218088Y0873632*
X1218096Y0873643*
X1218102Y0873655*
X1218108Y0873667*
X1218114Y087368*
X1218118Y0873693*
X1218121Y0873707*
X1218124Y087372*
X1218125Y0873734*
X1218126Y0873748*
X0721343Y091798D02*
D01*
X0721342Y0917993*
X0721341Y0918007*
X0721338Y091802*
X0721335Y0918034*
X0721331Y0918047*
X0721325Y091806*
X0721319Y0918072*
X0721313Y0918084*
X0721305Y0918095*
X0721296Y0918106*
X0721287Y0918116*
X0721277Y0918126*
X0721267Y0918135*
X0721256Y0918143*
X0721244Y091815*
X0721232Y0918157*
X0721219Y0918162*
X0721206Y0918167*
X0721193Y0918171*
X072118Y0918174*
X0721166Y0918175*
X0721152Y0918176*
X0721139*
X0721125Y0918175*
X0721111Y0918174*
X0721098Y0918171*
X0721085Y0918167*
X0721072Y0918162*
X0721059Y0918157*
X0721047Y091815*
X0721035Y0918143*
X0721024Y0918135*
X0721014Y0918126*
X0721004Y0918116*
X0720995Y0918106*
X0720986Y0918095*
X0720978Y0918084*
X0720972Y0918072*
X0720966Y091806*
X072096Y0918047*
X0720956Y0918034*
X0720953Y091802*
X072095Y0918007*
X0720949Y0917993*
X0720949Y091798*
X0720949Y0917966*
X072095Y0917952*
X0720953Y0917939*
X0720956Y0917925*
X072096Y0917912*
X0720966Y0917899*
X0720972Y0917887*
X0720978Y0917875*
X0720986Y0917864*
X0720995Y0917853*
X0721004Y0917843*
X0721014Y0917833*
X0721024Y0917824*
X0721035Y0917816*
X0721047Y0917809*
X0721059Y0917802*
X0721072Y0917797*
X0721085Y0917792*
X0721098Y0917788*
X0721111Y0917785*
X0721125Y0917784*
X0721139Y0917783*
X0721152*
X0721166Y0917784*
X072118Y0917785*
X0721193Y0917788*
X0721206Y0917792*
X0721219Y0917797*
X0721232Y0917802*
X0721244Y0917809*
X0721256Y0917816*
X0721267Y0917824*
X0721277Y0917833*
X0721287Y0917843*
X0721296Y0917853*
X0721305Y0917864*
X0721313Y0917875*
X0721319Y0917887*
X0721325Y0917899*
X0721331Y0917912*
X0721335Y0917925*
X0721338Y0917939*
X0721341Y0917952*
X0721342Y0917966*
X0721343Y091798*
X1187126Y0873748D02*
D01*
X1187125Y0873761*
X1187124Y0873775*
X1187121Y0873788*
X1187118Y0873802*
X1187114Y0873815*
X1187108Y0873828*
X1187102Y087384*
X1187096Y0873852*
X1187088Y0873863*
X1187079Y0873874*
X118707Y0873884*
X118706Y0873894*
X118705Y0873903*
X1187039Y0873911*
X1187027Y0873918*
X1187015Y0873925*
X1187002Y087393*
X1186989Y0873935*
X1186976Y0873939*
X1186963Y0873942*
X1186949Y0873943*
X1186935Y0873944*
X1186922*
X1186908Y0873943*
X1186894Y0873942*
X1186881Y0873939*
X1186868Y0873935*
X1186855Y087393*
X1186842Y0873925*
X118683Y0873918*
X1186818Y0873911*
X1186807Y0873903*
X1186797Y0873894*
X1186787Y0873884*
X1186778Y0873874*
X1186769Y0873863*
X1186761Y0873852*
X1186755Y087384*
X1186749Y0873828*
X1186743Y0873815*
X1186739Y0873802*
X1186736Y0873788*
X1186733Y0873775*
X1186732Y0873761*
X1186732Y0873748*
X1186732Y0873734*
X1186733Y087372*
X1186736Y0873707*
X1186739Y0873693*
X1186743Y087368*
X1186749Y0873667*
X1186755Y0873655*
X1186761Y0873643*
X1186769Y0873632*
X1186778Y0873621*
X1186787Y0873611*
X1186797Y0873601*
X1186807Y0873592*
X1186818Y0873584*
X118683Y0873577*
X1186842Y087357*
X1186855Y0873565*
X1186868Y087356*
X1186881Y0873556*
X1186894Y0873553*
X1186908Y0873552*
X1186922Y0873551*
X1186935*
X1186949Y0873552*
X1186963Y0873553*
X1186976Y0873556*
X1186989Y087356*
X1187002Y0873565*
X1187015Y087357*
X1187027Y0873577*
X1187039Y0873584*
X118705Y0873592*
X118706Y0873601*
X118707Y0873611*
X1187079Y0873621*
X1187088Y0873632*
X1187096Y0873643*
X1187102Y0873655*
X1187108Y0873667*
X1187114Y087368*
X1187118Y0873693*
X1187121Y0873707*
X1187124Y087372*
X1187125Y0873734*
X1187126Y0873748*
X1218626Y0860248D02*
D01*
X1218625Y0860261*
X1218624Y0860275*
X1218621Y0860288*
X1218618Y0860302*
X1218614Y0860315*
X1218608Y0860328*
X1218602Y086034*
X1218596Y0860352*
X1218588Y0860363*
X1218579Y0860374*
X121857Y0860384*
X121856Y0860394*
X121855Y0860403*
X1218539Y0860411*
X1218527Y0860418*
X1218515Y0860425*
X1218502Y086043*
X1218489Y0860435*
X1218476Y0860439*
X1218463Y0860442*
X1218449Y0860443*
X1218435Y0860444*
X1218422*
X1218408Y0860443*
X1218394Y0860442*
X1218381Y0860439*
X1218368Y0860435*
X1218355Y086043*
X1218342Y0860425*
X121833Y0860418*
X1218318Y0860411*
X1218307Y0860403*
X1218297Y0860394*
X1218287Y0860384*
X1218278Y0860374*
X1218269Y0860363*
X1218261Y0860352*
X1218255Y086034*
X1218249Y0860328*
X1218243Y0860315*
X1218239Y0860302*
X1218236Y0860288*
X1218233Y0860275*
X1218232Y0860261*
X1218232Y0860248*
X1218232Y0860234*
X1218233Y086022*
X1218236Y0860207*
X1218239Y0860193*
X1218243Y086018*
X1218249Y0860167*
X1218255Y0860155*
X1218261Y0860143*
X1218269Y0860132*
X1218278Y0860121*
X1218287Y0860111*
X1218297Y0860101*
X1218307Y0860092*
X1218318Y0860084*
X121833Y0860077*
X1218342Y086007*
X1218355Y0860065*
X1218368Y086006*
X1218381Y0860056*
X1218394Y0860053*
X1218408Y0860052*
X1218422Y0860051*
X1218435*
X1218449Y0860052*
X1218463Y0860053*
X1218476Y0860056*
X1218489Y086006*
X1218502Y0860065*
X1218515Y086007*
X1218527Y0860077*
X1218539Y0860084*
X121855Y0860092*
X121856Y0860101*
X121857Y0860111*
X1218579Y0860121*
X1218588Y0860132*
X1218596Y0860143*
X1218602Y0860155*
X1218608Y0860167*
X1218614Y086018*
X1218618Y0860193*
X1218621Y0860207*
X1218624Y086022*
X1218625Y0860234*
X1218626Y0860248*
X1027177Y0854854D02*
D01*
X1027176Y0854867*
X1027175Y0854881*
X1027172Y0854894*
X1027169Y0854908*
X1027165Y0854921*
X1027159Y0854934*
X1027153Y0854946*
X1027147Y0854958*
X1027139Y0854969*
X102713Y085498*
X1027121Y085499*
X1027111Y0855*
X1027101Y0855009*
X102709Y0855017*
X1027078Y0855024*
X1027066Y0855031*
X1027053Y0855036*
X102704Y0855041*
X1027027Y0855045*
X1027014Y0855048*
X1027Y0855049*
X1026986Y085505*
X1026973*
X1026959Y0855049*
X1026945Y0855048*
X1026932Y0855045*
X1026919Y0855041*
X1026906Y0855036*
X1026893Y0855031*
X1026881Y0855024*
X1026869Y0855017*
X1026858Y0855009*
X1026848Y0855*
X1026838Y085499*
X1026829Y085498*
X102682Y0854969*
X1026812Y0854958*
X1026806Y0854946*
X10268Y0854934*
X1026794Y0854921*
X102679Y0854908*
X1026787Y0854894*
X1026784Y0854881*
X1026783Y0854867*
X1026783Y0854854*
X1026783Y085484*
X1026784Y0854826*
X1026787Y0854813*
X102679Y0854799*
X1026794Y0854786*
X10268Y0854773*
X1026806Y0854761*
X1026812Y0854749*
X102682Y0854738*
X1026829Y0854727*
X1026838Y0854717*
X1026848Y0854707*
X1026858Y0854698*
X1026869Y085469*
X1026881Y0854683*
X1026893Y0854676*
X1026906Y0854671*
X1026919Y0854666*
X1026932Y0854662*
X1026945Y0854659*
X1026959Y0854658*
X1026973Y0854657*
X1026986*
X1027Y0854658*
X1027014Y0854659*
X1027027Y0854662*
X102704Y0854666*
X1027053Y0854671*
X1027066Y0854676*
X1027078Y0854683*
X102709Y085469*
X1027101Y0854698*
X1027111Y0854707*
X1027121Y0854717*
X102713Y0854727*
X1027139Y0854738*
X1027147Y0854749*
X1027153Y0854761*
X1027159Y0854773*
X1027165Y0854786*
X1027169Y0854799*
X1027172Y0854813*
X1027175Y0854826*
X1027176Y085484*
X1027177Y0854854*
X0961051Y089352D02*
D01*
X096105Y0893533*
X0961049Y0893547*
X0961046Y089356*
X0961043Y0893574*
X0961039Y0893587*
X0961033Y08936*
X0961027Y0893612*
X0961021Y0893624*
X0961013Y0893635*
X0961004Y0893646*
X0960995Y0893656*
X0960985Y0893666*
X0960975Y0893675*
X0960964Y0893683*
X0960952Y089369*
X096094Y0893697*
X0960927Y0893702*
X0960914Y0893707*
X0960901Y0893711*
X0960888Y0893714*
X0960874Y0893715*
X096086Y0893716*
X0960847*
X0960833Y0893715*
X0960819Y0893714*
X0960806Y0893711*
X0960793Y0893707*
X096078Y0893702*
X0960767Y0893697*
X0960755Y089369*
X0960743Y0893683*
X0960732Y0893675*
X0960722Y0893666*
X0960712Y0893656*
X0960703Y0893646*
X0960694Y0893635*
X0960686Y0893624*
X096068Y0893612*
X0960674Y08936*
X0960668Y0893587*
X0960664Y0893574*
X0960661Y089356*
X0960658Y0893547*
X0960657Y0893533*
X0960657Y089352*
X0960657Y0893506*
X0960658Y0893492*
X0960661Y0893479*
X0960664Y0893465*
X0960668Y0893452*
X0960674Y0893439*
X096068Y0893427*
X0960686Y0893415*
X0960694Y0893404*
X0960703Y0893393*
X0960712Y0893383*
X0960722Y0893373*
X0960732Y0893364*
X0960743Y0893356*
X0960755Y0893349*
X0960767Y0893342*
X096078Y0893337*
X0960793Y0893332*
X0960806Y0893328*
X0960819Y0893325*
X0960833Y0893324*
X0960847Y0893323*
X096086*
X0960874Y0893324*
X0960888Y0893325*
X0960901Y0893328*
X0960914Y0893332*
X0960927Y0893337*
X096094Y0893342*
X0960952Y0893349*
X0960964Y0893356*
X0960975Y0893364*
X0960985Y0893373*
X0960995Y0893383*
X0961004Y0893393*
X0961013Y0893404*
X0961021Y0893415*
X0961027Y0893427*
X0961033Y0893439*
X0961039Y0893452*
X0961043Y0893465*
X0961046Y0893479*
X0961049Y0893492*
X096105Y0893506*
X0961051Y089352*
X0955342Y087098D02*
D01*
X0955341Y0870993*
X095534Y0871007*
X0955337Y087102*
X0955334Y0871034*
X095533Y0871047*
X0955324Y087106*
X0955318Y0871072*
X0955312Y0871084*
X0955304Y0871095*
X0955295Y0871106*
X0955286Y0871116*
X0955276Y0871126*
X0955266Y0871135*
X0955255Y0871143*
X0955243Y087115*
X0955231Y0871157*
X0955218Y0871162*
X0955205Y0871167*
X0955192Y0871171*
X0955179Y0871174*
X0955165Y0871175*
X0955151Y0871176*
X0955138*
X0955124Y0871175*
X095511Y0871174*
X0955097Y0871171*
X0955084Y0871167*
X0955071Y0871162*
X0955058Y0871157*
X0955046Y087115*
X0955034Y0871143*
X0955023Y0871135*
X0955013Y0871126*
X0955003Y0871116*
X0954994Y0871106*
X0954985Y0871095*
X0954977Y0871084*
X0954971Y0871072*
X0954965Y087106*
X0954959Y0871047*
X0954955Y0871034*
X0954952Y087102*
X0954949Y0871007*
X0954948Y0870993*
X0954948Y087098*
X0954948Y0870966*
X0954949Y0870952*
X0954952Y0870939*
X0954955Y0870925*
X0954959Y0870912*
X0954965Y0870899*
X0954971Y0870887*
X0954977Y0870875*
X0954985Y0870864*
X0954994Y0870853*
X0955003Y0870843*
X0955013Y0870833*
X0955023Y0870824*
X0955034Y0870816*
X0955046Y0870809*
X0955058Y0870802*
X0955071Y0870797*
X0955084Y0870792*
X0955097Y0870788*
X095511Y0870785*
X0955124Y0870784*
X0955138Y0870783*
X0955151*
X0955165Y0870784*
X0955179Y0870785*
X0955192Y0870788*
X0955205Y0870792*
X0955218Y0870797*
X0955231Y0870802*
X0955243Y0870809*
X0955255Y0870816*
X0955266Y0870824*
X0955276Y0870833*
X0955286Y0870843*
X0955295Y0870853*
X0955304Y0870864*
X0955312Y0870875*
X0955318Y0870887*
X0955324Y0870899*
X095533Y0870912*
X0955334Y0870925*
X0955337Y0870939*
X095534Y0870952*
X0955341Y0870966*
X0955342Y087098*
X0660843Y091798D02*
D01*
X0660842Y0917993*
X0660841Y0918007*
X0660838Y091802*
X0660835Y0918034*
X0660831Y0918047*
X0660825Y091806*
X0660819Y0918072*
X0660813Y0918084*
X0660805Y0918095*
X0660796Y0918106*
X0660787Y0918116*
X0660777Y0918126*
X0660767Y0918135*
X0660756Y0918143*
X0660744Y091815*
X0660732Y0918157*
X0660719Y0918162*
X0660706Y0918167*
X0660693Y0918171*
X066068Y0918174*
X0660666Y0918175*
X0660652Y0918176*
X0660639*
X0660625Y0918175*
X0660611Y0918174*
X0660598Y0918171*
X0660585Y0918167*
X0660572Y0918162*
X0660559Y0918157*
X0660547Y091815*
X0660535Y0918143*
X0660524Y0918135*
X0660514Y0918126*
X0660504Y0918116*
X0660495Y0918106*
X0660486Y0918095*
X0660478Y0918084*
X0660472Y0918072*
X0660466Y091806*
X066046Y0918047*
X0660456Y0918034*
X0660453Y091802*
X066045Y0918007*
X0660449Y0917993*
X0660449Y091798*
X0660449Y0917966*
X066045Y0917952*
X0660453Y0917939*
X0660456Y0917925*
X066046Y0917912*
X0660466Y0917899*
X0660472Y0917887*
X0660478Y0917875*
X0660486Y0917864*
X0660495Y0917853*
X0660504Y0917843*
X0660514Y0917833*
X0660524Y0917824*
X0660535Y0917816*
X0660547Y0917809*
X0660559Y0917802*
X0660572Y0917797*
X0660585Y0917792*
X0660598Y0917788*
X0660611Y0917785*
X0660625Y0917784*
X0660639Y0917783*
X0660652*
X0660666Y0917784*
X066068Y0917785*
X0660693Y0917788*
X0660706Y0917792*
X0660719Y0917797*
X0660732Y0917802*
X0660744Y0917809*
X0660756Y0917816*
X0660767Y0917824*
X0660777Y0917833*
X0660787Y0917843*
X0660796Y0917853*
X0660805Y0917864*
X0660813Y0917875*
X0660819Y0917887*
X0660825Y0917899*
X0660831Y0917912*
X0660835Y0917925*
X0660838Y0917939*
X0660841Y0917952*
X0660842Y0917966*
X0660843Y091798*
X0681009D02*
D01*
X0681008Y0917993*
X0681007Y0918007*
X0681004Y091802*
X0681001Y0918034*
X0680997Y0918047*
X0680991Y091806*
X0680985Y0918072*
X0680979Y0918084*
X0680971Y0918095*
X0680962Y0918106*
X0680953Y0918116*
X0680943Y0918126*
X0680933Y0918135*
X0680922Y0918143*
X068091Y091815*
X0680898Y0918157*
X0680885Y0918162*
X0680872Y0918167*
X0680859Y0918171*
X0680846Y0918174*
X0680832Y0918175*
X0680818Y0918176*
X0680805*
X0680791Y0918175*
X0680777Y0918174*
X0680764Y0918171*
X0680751Y0918167*
X0680738Y0918162*
X0680725Y0918157*
X0680713Y091815*
X0680701Y0918143*
X068069Y0918135*
X068068Y0918126*
X068067Y0918116*
X0680661Y0918106*
X0680652Y0918095*
X0680644Y0918084*
X0680638Y0918072*
X0680632Y091806*
X0680626Y0918047*
X0680622Y0918034*
X0680619Y091802*
X0680616Y0918007*
X0680615Y0917993*
X0680615Y091798*
X0680615Y0917966*
X0680616Y0917952*
X0680619Y0917939*
X0680622Y0917925*
X0680626Y0917912*
X0680632Y0917899*
X0680638Y0917887*
X0680644Y0917875*
X0680652Y0917864*
X0680661Y0917853*
X068067Y0917843*
X068068Y0917833*
X068069Y0917824*
X0680701Y0917816*
X0680713Y0917809*
X0680725Y0917802*
X0680738Y0917797*
X0680751Y0917792*
X0680764Y0917788*
X0680777Y0917785*
X0680791Y0917784*
X0680805Y0917783*
X0680818*
X0680832Y0917784*
X0680846Y0917785*
X0680859Y0917788*
X0680872Y0917792*
X0680885Y0917797*
X0680898Y0917802*
X068091Y0917809*
X0680922Y0917816*
X0680933Y0917824*
X0680943Y0917833*
X0680953Y0917843*
X0680962Y0917853*
X0680971Y0917864*
X0680979Y0917875*
X0680985Y0917887*
X0680991Y0917899*
X0680997Y0917912*
X0681001Y0917925*
X0681004Y0917939*
X0681007Y0917952*
X0681008Y0917966*
X0681009Y091798*
X0701176D02*
D01*
X0701175Y0917993*
X0701174Y0918007*
X0701171Y091802*
X0701168Y0918034*
X0701164Y0918047*
X0701158Y091806*
X0701152Y0918072*
X0701146Y0918084*
X0701138Y0918095*
X0701129Y0918106*
X070112Y0918116*
X070111Y0918126*
X07011Y0918135*
X0701089Y0918143*
X0701077Y091815*
X0701065Y0918157*
X0701052Y0918162*
X0701039Y0918167*
X0701026Y0918171*
X0701013Y0918174*
X0700999Y0918175*
X0700985Y0918176*
X0700972*
X0700958Y0918175*
X0700944Y0918174*
X0700931Y0918171*
X0700918Y0918167*
X0700905Y0918162*
X0700892Y0918157*
X070088Y091815*
X0700868Y0918143*
X0700857Y0918135*
X0700847Y0918126*
X0700837Y0918116*
X0700828Y0918106*
X0700819Y0918095*
X0700811Y0918084*
X0700805Y0918072*
X0700799Y091806*
X0700793Y0918047*
X0700789Y0918034*
X0700786Y091802*
X0700783Y0918007*
X0700782Y0917993*
X0700782Y091798*
X0700782Y0917966*
X0700783Y0917952*
X0700786Y0917939*
X0700789Y0917925*
X0700793Y0917912*
X0700799Y0917899*
X0700805Y0917887*
X0700811Y0917875*
X0700819Y0917864*
X0700828Y0917853*
X0700837Y0917843*
X0700847Y0917833*
X0700857Y0917824*
X0700868Y0917816*
X070088Y0917809*
X0700892Y0917802*
X0700905Y0917797*
X0700918Y0917792*
X0700931Y0917788*
X0700944Y0917785*
X0700958Y0917784*
X0700972Y0917783*
X0700985*
X0700999Y0917784*
X0701013Y0917785*
X0701026Y0917788*
X0701039Y0917792*
X0701052Y0917797*
X0701065Y0917802*
X0701077Y0917809*
X0701089Y0917816*
X07011Y0917824*
X070111Y0917833*
X070112Y0917843*
X0701129Y0917853*
X0701138Y0917864*
X0701146Y0917875*
X0701152Y0917887*
X0701158Y0917899*
X0701164Y0917912*
X0701168Y0917925*
X0701171Y0917939*
X0701174Y0917952*
X0701175Y0917966*
X0701176Y091798*
G54D14*
X1267Y08135D02*
D01*
X1266998Y0813534*
X1266995Y0813569*
X1266989Y0813603*
X126698Y0813637*
X1266969Y0813671*
X1266956Y0813703*
X1266941Y0813734*
X1266924Y0813764*
X1266904Y0813793*
X1266883Y0813821*
X1266859Y0813847*
X1266834Y0813871*
X1266807Y0813894*
X1266779Y0813914*
X126675Y0813933*
X1266719Y0813949*
X1266687Y0813963*
X1266654Y0813975*
X126662Y0813985*
X1266586Y0813992*
X1266552Y0813997*
X1266517Y0813999*
X1266482*
X1266447Y0813997*
X1266413Y0813992*
X1266379Y0813985*
X1266345Y0813975*
X1266312Y0813963*
X126628Y0813949*
X126625Y0813933*
X126622Y0813914*
X1266192Y0813894*
X1266165Y0813871*
X126614Y0813847*
X1266116Y0813821*
X1266095Y0813793*
X1266075Y0813764*
X1266058Y0813734*
X1266043Y0813703*
X126603Y0813671*
X1266019Y0813637*
X126601Y0813603*
X1266004Y0813569*
X1266001Y0813534*
X1266Y08135*
X1266001Y0813465*
X1266004Y081343*
X126601Y0813396*
X1266019Y0813362*
X126603Y0813328*
X1266043Y0813296*
X1266058Y0813265*
X1266075Y0813235*
X1266095Y0813206*
X1266116Y0813178*
X126614Y0813152*
X1266165Y0813128*
X1266192Y0813105*
X126622Y0813085*
X126625Y0813066*
X126628Y081305*
X1266312Y0813036*
X1266345Y0813024*
X1266379Y0813014*
X1266413Y0813007*
X1266447Y0813002*
X1266482Y0813*
X1266517*
X1266552Y0813002*
X1266586Y0813007*
X126662Y0813014*
X1266654Y0813024*
X1266687Y0813036*
X1266719Y081305*
X126675Y0813066*
X1266779Y0813085*
X1266807Y0813105*
X1266834Y0813128*
X1266859Y0813152*
X1266883Y0813178*
X1266904Y0813206*
X1266924Y0813235*
X1266941Y0813265*
X1266956Y0813296*
X1266969Y0813328*
X126698Y0813362*
X1266989Y0813396*
X1266995Y081343*
X1266998Y0813465*
X1267Y08135*
X1011996Y0660356D02*
D01*
X1011994Y066039*
X1011991Y0660425*
X1011985Y0660459*
X1011976Y0660493*
X1011965Y0660527*
X1011952Y0660559*
X1011937Y066059*
X101192Y066062*
X10119Y0660649*
X1011879Y0660677*
X1011855Y0660703*
X101183Y0660727*
X1011803Y066075*
X1011775Y066077*
X1011746Y0660789*
X1011715Y0660805*
X1011683Y0660819*
X101165Y0660831*
X1011616Y0660841*
X1011582Y0660848*
X1011548Y0660853*
X1011513Y0660855*
X1011478*
X1011443Y0660853*
X1011409Y0660848*
X1011375Y0660841*
X1011341Y0660831*
X1011308Y0660819*
X1011276Y0660805*
X1011246Y0660789*
X1011216Y066077*
X1011188Y066075*
X1011161Y0660727*
X1011136Y0660703*
X1011112Y0660677*
X1011091Y0660649*
X1011071Y066062*
X1011054Y066059*
X1011039Y0660559*
X1011026Y0660527*
X1011015Y0660493*
X1011006Y0660459*
X1011Y0660425*
X1010997Y066039*
X1010996Y0660356*
X1010997Y0660321*
X1011Y0660286*
X1011006Y0660252*
X1011015Y0660218*
X1011026Y0660184*
X1011039Y0660152*
X1011054Y0660121*
X1011071Y0660091*
X1011091Y0660062*
X1011112Y0660034*
X1011136Y0660008*
X1011161Y0659984*
X1011188Y0659961*
X1011216Y0659941*
X1011246Y0659922*
X1011276Y0659906*
X1011308Y0659892*
X1011341Y065988*
X1011375Y065987*
X1011409Y0659863*
X1011443Y0659858*
X1011478Y0659856*
X1011513*
X1011548Y0659858*
X1011582Y0659863*
X1011616Y065987*
X101165Y065988*
X1011683Y0659892*
X1011715Y0659906*
X1011746Y0659922*
X1011775Y0659941*
X1011803Y0659961*
X101183Y0659984*
X1011855Y0660008*
X1011879Y0660034*
X10119Y0660062*
X101192Y0660091*
X1011937Y0660121*
X1011952Y0660152*
X1011965Y0660184*
X1011976Y0660218*
X1011985Y0660252*
X1011991Y0660286*
X1011994Y0660321*
X1011996Y0660356*
X1096247Y0806279D02*
D01*
X1098707Y080715*
X1101101Y0808191*
X1103417Y0809396*
X1105643Y081076*
X1107768Y0812276*
X1109783Y0813937*
X1111677Y0815734*
X111344Y0817659*
X1115065Y0819702*
X1116544Y0821853*
X1117869Y0824103*
X1119034Y0826439*
X1120033Y0828851*
X1120861Y0831327*
X1121515Y0833854*
X1121991Y0836421*
X1122286Y0839015*
X11224Y0841623*
X1122332Y0844233*
X1122082Y0846831*
X1121651Y0849406*
X1121041Y0851945*
X1120256Y0854435*
X1119299Y0856864*
X1118176Y085922*
X111689Y0861492*
X1115449Y0863669*
X111386Y086574*
X111213Y0867695*
X1110268Y0869525*
X1108283Y0871221*
X1106184Y0872774*
X1103983Y0874176*
X1101688Y0875422*
X1099313Y0876505*
X1096867Y0877419*
X1096247Y087762*
X1073753D02*
D01*
X1071292Y0876748*
X1068898Y0875707*
X1066582Y0874502*
X1064356Y0873138*
X1062231Y0871622*
X1060216Y0869961*
X1058322Y0868164*
X1056559Y0866239*
X1054934Y0864196*
X1053455Y0862045*
X105213Y0859795*
X1050965Y0857459*
X1049966Y0855047*
X1049138Y0852571*
X1048484Y0850044*
X1048008Y0847477*
X1047713Y0844883*
X1047599Y0842275*
X1047667Y0839665*
X1047917Y0837067*
X1048348Y0834492*
X1048958Y0831953*
X1049743Y0829463*
X10507Y0827034*
X1051823Y0824678*
X1053109Y0822406*
X105455Y0820229*
X1056139Y0818158*
X1057869Y0816203*
X1059731Y0814373*
X1061716Y0812677*
X1063815Y0811124*
X1066016Y0809722*
X1068311Y0808476*
X1070686Y0807393*
X1073132Y0806479*
X1073753Y0806279*
X0857758Y0783539D02*
D01*
X0857743Y0783964*
X0857698Y0784388*
X0857624Y0784807*
X0857521Y078522*
X085739Y0785626*
X085723Y078602*
X0857043Y0786403*
X085683Y0786772*
X0856592Y0787125*
X085633Y0787461*
X0856045Y0787777*
X0855739Y0788073*
X0855412Y0788347*
X0855068Y0788597*
X0854707Y0788823*
X085433Y0789023*
X0853941Y0789196*
X0853541Y0789342*
X0853132Y0789459*
X0852715Y0789548*
X0852293Y0789607*
X0851868Y0789637*
X0851443*
X0851018Y0789607*
X0850596Y0789548*
X0850179Y0789459*
X084977Y0789342*
X084937Y0789196*
X0848981Y0789023*
X0848605Y0788823*
X0848243Y0788597*
X0847899Y0788347*
X0847572Y0788073*
X0847266Y0787777*
X0846981Y0787461*
X0846719Y0787125*
X0846481Y0786772*
X0846268Y0786403*
X0846081Y078602*
X0845921Y0785626*
X084579Y078522*
X0845687Y0784807*
X0845613Y0784388*
X0845568Y0783964*
X0845554Y0783539*
X0845568Y0783113*
X0845613Y0782689*
X0845687Y078227*
X084579Y0781857*
X0845921Y0781451*
X0846081Y0781057*
X0846268Y0780674*
X0846481Y0780305*
X0846719Y0779952*
X0846981Y0779616*
X0847266Y07793*
X0847572Y0779004*
X0847899Y077873*
X0848243Y077848*
X0848605Y0778254*
X0848981Y0778054*
X084937Y0777881*
X084977Y0777735*
X0850179Y0777618*
X0850596Y0777529*
X0851018Y077747*
X0851443Y077744*
X0851868*
X0852293Y077747*
X0852715Y0777529*
X0853132Y0777618*
X0853541Y0777735*
X0853941Y0777881*
X085433Y0778054*
X0854707Y0778254*
X0855068Y077848*
X0855412Y077873*
X0855739Y0779004*
X0856045Y07793*
X085633Y0779616*
X0856592Y0779952*
X085683Y0780305*
X0857043Y0780674*
X085723Y0781057*
X085739Y0781451*
X0857521Y0781857*
X0857624Y078227*
X0857698Y0782689*
X0857743Y0783113*
X0857758Y0783539*
Y0885902D02*
D01*
X0857743Y0886327*
X0857698Y0886751*
X0857624Y088717*
X0857521Y0887583*
X085739Y0887989*
X085723Y0888383*
X0857043Y0888766*
X085683Y0889135*
X0856592Y0889488*
X085633Y0889824*
X0856045Y089014*
X0855739Y0890436*
X0855412Y089071*
X0855068Y089096*
X0854707Y0891186*
X085433Y0891386*
X0853941Y0891559*
X0853541Y0891705*
X0853132Y0891822*
X0852715Y0891911*
X0852293Y089197*
X0851868Y0892*
X0851443*
X0851018Y089197*
X0850596Y0891911*
X0850179Y0891822*
X084977Y0891705*
X084937Y0891559*
X0848981Y0891386*
X0848605Y0891186*
X0848243Y089096*
X0847899Y089071*
X0847572Y0890436*
X0847266Y089014*
X0846981Y0889824*
X0846719Y0889488*
X0846481Y0889135*
X0846268Y0888766*
X0846081Y0888383*
X0845921Y0887989*
X084579Y0887583*
X0845687Y088717*
X0845613Y0886751*
X0845568Y0886327*
X0845554Y0885902*
X0845568Y0885476*
X0845613Y0885052*
X0845687Y0884633*
X084579Y088422*
X0845921Y0883814*
X0846081Y088342*
X0846268Y0883037*
X0846481Y0882668*
X0846719Y0882315*
X0846981Y0881979*
X0847266Y0881663*
X0847572Y0881367*
X0847899Y0881093*
X0848243Y0880843*
X0848605Y0880617*
X0848981Y0880417*
X084937Y0880244*
X084977Y0880098*
X0850179Y0879981*
X0850596Y0879892*
X0851018Y0879833*
X0851443Y0879803*
X0851868*
X0852293Y0879833*
X0852715Y0879892*
X0853132Y0879981*
X0853541Y0880098*
X0853941Y0880244*
X085433Y0880417*
X0854707Y0880617*
X0855068Y0880843*
X0855412Y0881093*
X0855739Y0881367*
X0856045Y0881663*
X085633Y0881979*
X0856592Y0882315*
X085683Y0882668*
X0857043Y0883037*
X085723Y088342*
X085739Y0883814*
X0857521Y088422*
X0857624Y0884633*
X0857698Y0885052*
X0857743Y0885476*
X0857758Y0885902*
X0619569D02*
D01*
X0619554Y0886327*
X0619509Y0886751*
X0619435Y088717*
X0619332Y0887583*
X0619201Y0887989*
X0619041Y0888383*
X0618854Y0888766*
X0618641Y0889135*
X0618403Y0889488*
X0618141Y0889824*
X0617856Y089014*
X061755Y0890436*
X0617223Y089071*
X0616879Y089096*
X0616518Y0891186*
X0616141Y0891386*
X0615752Y0891559*
X0615352Y0891705*
X0614943Y0891822*
X0614526Y0891911*
X0614104Y089197*
X0613679Y0892*
X0613254*
X0612829Y089197*
X0612407Y0891911*
X061199Y0891822*
X0611581Y0891705*
X0611181Y0891559*
X0610792Y0891386*
X0610416Y0891186*
X0610054Y089096*
X060971Y089071*
X0609383Y0890436*
X0609077Y089014*
X0608792Y0889824*
X060853Y0889488*
X0608292Y0889135*
X0608079Y0888766*
X0607892Y0888383*
X0607732Y0887989*
X0607601Y0887583*
X0607498Y088717*
X0607424Y0886751*
X0607379Y0886327*
X0607365Y0885902*
X0607379Y0885476*
X0607424Y0885052*
X0607498Y0884633*
X0607601Y088422*
X0607732Y0883814*
X0607892Y088342*
X0608079Y0883037*
X0608292Y0882668*
X060853Y0882315*
X0608792Y0881979*
X0609077Y0881663*
X0609383Y0881367*
X060971Y0881093*
X0610054Y0880843*
X0610416Y0880617*
X0610792Y0880417*
X0611181Y0880244*
X0611581Y0880098*
X061199Y0879981*
X0612407Y0879892*
X0612829Y0879833*
X0613254Y0879803*
X0613679*
X0614104Y0879833*
X0614526Y0879892*
X0614943Y0879981*
X0615352Y0880098*
X0615752Y0880244*
X0616141Y0880417*
X0616518Y0880617*
X0616879Y0880843*
X0617223Y0881093*
X061755Y0881367*
X0617856Y0881663*
X0618141Y0881979*
X0618403Y0882315*
X0618641Y0882668*
X0618854Y0883037*
X0619041Y088342*
X0619201Y0883814*
X0619332Y088422*
X0619435Y0884633*
X0619509Y0885052*
X0619554Y0885476*
X0619569Y0885902*
Y0783539D02*
D01*
X0619554Y0783964*
X0619509Y0784388*
X0619435Y0784807*
X0619332Y078522*
X0619201Y0785626*
X0619041Y078602*
X0618854Y0786403*
X0618641Y0786772*
X0618403Y0787125*
X0618141Y0787461*
X0617856Y0787777*
X061755Y0788073*
X0617223Y0788347*
X0616879Y0788597*
X0616518Y0788823*
X0616141Y0789023*
X0615752Y0789196*
X0615352Y0789342*
X0614943Y0789459*
X0614526Y0789548*
X0614104Y0789607*
X0613679Y0789637*
X0613254*
X0612829Y0789607*
X0612407Y0789548*
X061199Y0789459*
X0611581Y0789342*
X0611181Y0789196*
X0610792Y0789023*
X0610416Y0788823*
X0610054Y0788597*
X060971Y0788347*
X0609383Y0788073*
X0609077Y0787777*
X0608792Y0787461*
X060853Y0787125*
X0608292Y0786772*
X0608079Y0786403*
X0607892Y078602*
X0607732Y0785626*
X0607601Y078522*
X0607498Y0784807*
X0607424Y0784388*
X0607379Y0783964*
X0607365Y0783539*
X0607379Y0783113*
X0607424Y0782689*
X0607498Y078227*
X0607601Y0781857*
X0607732Y0781451*
X0607892Y0781057*
X0608079Y0780674*
X0608292Y0780305*
X060853Y0779952*
X0608792Y0779616*
X0609077Y07793*
X0609383Y0779004*
X060971Y077873*
X0610054Y077848*
X0610416Y0778254*
X0610792Y0778054*
X0611181Y0777881*
X0611581Y0777735*
X061199Y0777618*
X0612407Y0777529*
X0612829Y077747*
X0613254Y077744*
X0613679*
X0614104Y077747*
X0614526Y0777529*
X0614943Y0777618*
X0615352Y0777735*
X0615752Y0777881*
X0616141Y0778054*
X0616518Y0778254*
X0616879Y077848*
X0617223Y077873*
X061755Y0779004*
X0617856Y07793*
X0618141Y0779616*
X0618403Y0779952*
X0618641Y0780305*
X0618854Y0780674*
X0619041Y0781057*
X0619201Y0781451*
X0619332Y0781857*
X0619435Y078227*
X0619509Y0782689*
X0619554Y0783113*
X0619569Y0783539*
X117691Y0569377D02*
Y0769377D01*
X097691Y0569377D02*
X117691D01*
X097691D02*
Y0769377D01*
X117691*
X125248Y08135D02*
Y08355D01*
X12355Y08135D02*
X125248D01*
X12355D02*
Y08355D01*
X125248*
X1241803Y0787803D02*
X1292197D01*
X1241803Y0735197D02*
Y0787803D01*
Y0735197D02*
X1292197D01*
Y0787803*
X1061378Y0780926D02*
X1073189D01*
X1096811D02*
X1108622D01*
X1053504Y0820296D02*
X1061378Y0780926D01*
X1108622D02*
X1116496Y0820296D01*
X1205803Y0639197D02*
X1256197D01*
Y0691803*
X1205803D02*
X1256197D01*
X1205803Y0639197D02*
Y0691803D01*
X0864805Y0772221D02*
Y0897221D01*
X0600317D02*
X0864805D01*
X0600317Y0772221D02*
Y0897221D01*
Y0772221D02*
X0864805D01*
X0839272Y0913058D02*
Y0911058D01*
Y0912058*
X0845271*
X0844271Y0913058*
X0997461Y0897764D02*
X0995461D01*
X0996461*
Y0891766*
X0997461Y0892765*
X0808858Y0593848D02*
Y0599846D01*
X0805859Y0596847*
X0809858*
X0765859Y0723846D02*
X0766859Y0724846D01*
X0768858*
X0769858Y0723846*
Y0722847*
X0768858Y0721847*
X0767858*
X0768858*
X0769858Y0720847*
Y0719848*
X0768858Y0718848*
X0766859*
X0765859Y0719848*
X0809858Y0741348D02*
X0805859D01*
X0809858Y0745347*
Y0746346*
X0808858Y0747346*
X0806859*
X0805859Y0746346*
X0953359Y0718848D02*
X0955358D01*
X0954359*
Y0724846*
X0953359Y0723846*
G54D15*
X0886Y0886504D02*
D01*
X0885993Y0886678*
X0885975Y0886851*
X0885945Y0887023*
X0885903Y0887193*
X0885849Y0887359*
X0885783Y088752*
X0885707Y0887677*
X088562Y0887828*
X0885522Y0887973*
X0885415Y088811*
X0885298Y088824*
X0885172Y0888361*
X0885039Y0888474*
X0884897Y0888576*
X088475Y0888669*
X0884595Y088875*
X0884436Y0888821*
X0884272Y0888881*
X0884104Y0888929*
X0883934Y0888966*
X0883761Y088899*
X0883587Y0889002*
X0883412*
X0883238Y088899*
X0883065Y0888966*
X0882895Y0888929*
X0882727Y0888881*
X0882563Y0888821*
X0882404Y088875*
X088225Y0888669*
X0882102Y0888576*
X088196Y0888474*
X0881827Y0888361*
X0881701Y088824*
X0881584Y088811*
X0881477Y0887973*
X0881379Y0887828*
X0881292Y0887677*
X0881216Y088752*
X088115Y0887359*
X0881096Y0887193*
X0881054Y0887023*
X0881024Y0886851*
X0881006Y0886678*
X0881Y0886504*
X0881006Y0886329*
X0881024Y0886156*
X0881054Y0885984*
X0881096Y0885814*
X088115Y0885648*
X0881216Y0885487*
X0881292Y088533*
X0881379Y0885179*
X0881477Y0885034*
X0881584Y0884897*
X0881701Y0884767*
X0881827Y0884646*
X088196Y0884533*
X0882102Y0884431*
X088225Y0884338*
X0882404Y0884257*
X0882563Y0884186*
X0882727Y0884126*
X0882895Y0884078*
X0883065Y0884041*
X0883238Y0884017*
X0883412Y0884005*
X0883587*
X0883761Y0884017*
X0883934Y0884041*
X0884104Y0884078*
X0884272Y0884126*
X0884436Y0884186*
X0884595Y0884257*
X088475Y0884338*
X0884897Y0884431*
X0885039Y0884533*
X0885172Y0884646*
X0885298Y0884767*
X0885415Y0884897*
X0885522Y0885034*
X088562Y0885179*
X0885707Y088533*
X0885783Y0885487*
X0885849Y0885648*
X0885903Y0885814*
X0885945Y0885984*
X0885975Y0886156*
X0885993Y0886329*
X0886Y0886504*
X0950331Y0868342D02*
Y0872279D01*
X0948559Y0868342D02*
X0950331D01*
X0941669D02*
Y0872279D01*
Y0868342D02*
X0943441D01*
X0766601Y0901758D02*
Y0921443D01*
X0779199Y0901758D02*
Y0921443D01*
X0766601D02*
X0779199D01*
X0766601Y0901758D02*
X0779199D01*
X1219898Y087424D02*
X1232102D01*
X1219898Y086676D02*
X1232102D01*
X1219898Y0873748D02*
Y087424D01*
X1232102Y0873748D02*
Y087424D01*
X1219898Y086676D02*
Y0867252D01*
X1232102Y086676D02*
Y0867252D01*
X08735Y0890756D02*
Y0927252D01*
X09535Y0890756D02*
Y0927252D01*
X08735D02*
X0889622D01*
X0937378D02*
X09535D01*
X0937378Y0890756D02*
X09535D01*
X08735D02*
X0889622D01*
X0877264Y0806264D02*
Y0806559D01*
Y0806264D02*
X0877559D01*
X0897441D02*
X0897736D01*
Y0806559*
Y0826441D02*
Y0826736D01*
X0897441D02*
X0897736D01*
X0877264D02*
X0877559D01*
X0877264Y0826441D02*
Y0826736D01*
X0689327Y0598776D02*
Y0603402D01*
X0717673Y0598776D02*
Y0603402D01*
X0689327Y0578598D02*
Y0583224D01*
X0717673Y0578598D02*
Y0583224D01*
X0689327Y0603402D02*
X0717673D01*
X0689327Y0578598D02*
X0717673D01*
X1188898Y087424D02*
X1201102D01*
X1188898Y086676D02*
X1201102D01*
X1188898Y0873748D02*
Y087424D01*
X1201102Y0873748D02*
Y087424D01*
X1188898Y086676D02*
Y0867252D01*
X1201102Y086676D02*
Y0867252D01*
X1220398Y086074D02*
X1232602D01*
X1220398Y085326D02*
X1232602D01*
X1220398Y0860248D02*
Y086074D01*
X1232602Y0860248D02*
Y086074D01*
X1220398Y085326D02*
Y0853752D01*
X1232602Y085326D02*
Y0853752D01*
X0886831Y0868342D02*
Y0872279D01*
X0885059Y0868342D02*
X0886831D01*
X0878169D02*
Y0872279D01*
Y0868342D02*
X0879941D01*
X0875331D02*
Y0872279D01*
X0873559Y0868342D02*
X0875331D01*
X0866669D02*
Y0872279D01*
Y0868342D02*
X0868441D01*
X0927831D02*
Y0872279D01*
X0926059Y0868342D02*
X0927831D01*
X0919169D02*
Y0872279D01*
Y0868342D02*
X0920941D01*
X0689327Y0683598D02*
X0717673D01*
X0689327Y0708402D02*
X0717673D01*
Y0683598D02*
Y0688224D01*
X0689327Y0683598D02*
Y0688224D01*
X0717673Y0703776D02*
Y0708402D01*
X0689327Y0703776D02*
Y0708402D01*
Y0736098D02*
X0717673D01*
X0689327Y0760902D02*
X0717673D01*
Y0736098D02*
Y0740724D01*
X0689327Y0736098D02*
Y0740724D01*
X0717673Y0756276D02*
Y0760902D01*
X0689327Y0756276D02*
Y0760902D01*
Y0651276D02*
Y0655902D01*
X0717673Y0651276D02*
Y0655902D01*
X0689327Y0631098D02*
Y0635724D01*
X0717673Y0631098D02*
Y0635724D01*
X0689327Y0655902D02*
X0717673D01*
X0689327Y0631098D02*
X0717673D01*
X0980701Y0867657D02*
Y0887342D01*
X0993299Y0867657D02*
Y0887342D01*
X0980701D02*
X0993299D01*
X0980701Y0867657D02*
X0993299D01*
G54D16*
X1211787Y0874504D02*
D01*
X1211785Y0874558*
X1211779Y0874613*
X1211769Y0874667*
X1211756Y087472*
X1211739Y0874773*
X1211718Y0874824*
X1211694Y0874873*
X1211667Y0874921*
X1211636Y0874966*
X1211602Y0875009*
X1211566Y087505*
X1211526Y0875088*
X1211484Y0875124*
X121144Y0875156*
X1211393Y0875185*
X1211344Y0875211*
X1211294Y0875233*
X1211243Y0875252*
X121119Y0875267*
X1211136Y0875279*
X1211082Y0875286*
X1211027Y087529*
X1210972*
X1210917Y0875286*
X1210863Y0875279*
X1210809Y0875267*
X1210756Y0875252*
X1210705Y0875233*
X1210655Y0875211*
X1210606Y0875185*
X1210559Y0875156*
X1210515Y0875124*
X1210473Y0875088*
X1210433Y087505*
X1210397Y0875009*
X1210363Y0874966*
X1210332Y0874921*
X1210305Y0874873*
X1210281Y0874824*
X121026Y0874773*
X1210243Y087472*
X121023Y0874667*
X121022Y0874613*
X1210214Y0874558*
X1210213Y0874504*
X1210214Y0874449*
X121022Y0874394*
X121023Y087434*
X1210243Y0874287*
X121026Y0874234*
X1210281Y0874183*
X1210305Y0874134*
X1210332Y0874086*
X1210363Y0874041*
X1210397Y0873998*
X1210433Y0873957*
X1210473Y0873919*
X1210515Y0873883*
X1210559Y0873851*
X1210606Y0873822*
X1210655Y0873796*
X1210705Y0873774*
X1210756Y0873755*
X1210809Y087374*
X1210863Y0873728*
X1210917Y0873721*
X1210972Y0873717*
X1211027*
X1211082Y0873721*
X1211136Y0873728*
X121119Y087374*
X1211243Y0873755*
X1211294Y0873774*
X1211344Y0873796*
X1211393Y0873822*
X121144Y0873851*
X1211484Y0873883*
X1211526Y0873919*
X1211566Y0873957*
X1211602Y0873998*
X1211636Y0874041*
X1211667Y0874086*
X1211694Y0874134*
X1211718Y0874183*
X1211739Y0874234*
X1211756Y0874287*
X1211769Y087434*
X1211779Y0874394*
X1211785Y0874449*
X1211787Y0874504*
G54D17*
X0897974Y0610053D02*
D01*
X0897972Y0610107*
X0897966Y0610162*
X0897956Y0610216*
X0897943Y061027*
X0897926Y0610322*
X0897905Y0610373*
X0897881Y0610422*
X0897854Y061047*
X0897823Y0610516*
X0897789Y0610559*
X0897752Y06106*
X0897713Y0610638*
X0897671Y0610673*
X0897626Y0610706*
X089758Y0610735*
X0897531Y0610761*
X0897481Y0610783*
X0897429Y0610802*
X0897376Y0610817*
X0897322Y0610829*
X0897268Y0610836*
X0897213Y061084*
X0897158*
X0897103Y0610836*
X0897049Y0610829*
X0896995Y0610817*
X0896942Y0610802*
X089689Y0610783*
X089684Y0610761*
X0896792Y0610735*
X0896745Y0610706*
X08967Y0610673*
X0896658Y0610638*
X0896619Y06106*
X0896582Y0610559*
X0896548Y0610516*
X0896517Y061047*
X089649Y0610422*
X0896466Y0610373*
X0896445Y0610322*
X0896428Y061027*
X0896415Y0610216*
X0896405Y0610162*
X0896399Y0610107*
X0896398Y0610053*
X0896399Y0609998*
X0896405Y0609943*
X0896415Y0609889*
X0896428Y0609835*
X0896445Y0609783*
X0896466Y0609732*
X089649Y0609683*
X0896517Y0609635*
X0896548Y0609589*
X0896582Y0609546*
X0896619Y0609505*
X0896658Y0609467*
X08967Y0609432*
X0896745Y0609399*
X0896792Y060937*
X089684Y0609344*
X089689Y0609322*
X0896942Y0609303*
X0896995Y0609288*
X0897049Y0609276*
X0897103Y0609269*
X0897158Y0609265*
X0897213*
X0897268Y0609269*
X0897322Y0609276*
X0897376Y0609288*
X0897429Y0609303*
X0897481Y0609322*
X0897531Y0609344*
X089758Y060937*
X0897626Y0609399*
X0897671Y0609432*
X0897713Y0609467*
X0897752Y0609505*
X0897789Y0609546*
X0897823Y0609589*
X0897854Y0609635*
X0897881Y0609683*
X0897905Y0609732*
X0897926Y0609783*
X0897943Y0609835*
X0897956Y0609889*
X0897966Y0609943*
X0897972Y0609998*
X0897974Y0610053*
X0783287Y0632261D02*
D01*
X0783285Y0632315*
X0783279Y063237*
X0783269Y0632424*
X0783256Y0632478*
X0783239Y063253*
X0783218Y0632581*
X0783194Y063263*
X0783167Y0632678*
X0783136Y0632724*
X0783102Y0632767*
X0783065Y0632808*
X0783026Y0632846*
X0782984Y0632881*
X0782939Y0632914*
X0782893Y0632943*
X0782844Y0632969*
X0782794Y0632991*
X0782742Y063301*
X0782689Y0633025*
X0782635Y0633037*
X0782581Y0633044*
X0782526Y0633048*
X0782471*
X0782416Y0633044*
X0782362Y0633037*
X0782308Y0633025*
X0782255Y063301*
X0782203Y0632991*
X0782153Y0632969*
X0782105Y0632943*
X0782058Y0632914*
X0782013Y0632881*
X0781971Y0632846*
X0781932Y0632808*
X0781895Y0632767*
X0781861Y0632724*
X078183Y0632678*
X0781803Y063263*
X0781779Y0632581*
X0781758Y063253*
X0781741Y0632478*
X0781728Y0632424*
X0781718Y063237*
X0781712Y0632315*
X0781711Y0632261*
X0781712Y0632206*
X0781718Y0632151*
X0781728Y0632097*
X0781741Y0632043*
X0781758Y0631991*
X0781779Y063194*
X0781803Y0631891*
X078183Y0631843*
X0781861Y0631797*
X0781895Y0631754*
X0781932Y0631713*
X0781971Y0631675*
X0782013Y063164*
X0782058Y0631607*
X0782105Y0631578*
X0782153Y0631552*
X0782203Y063153*
X0782255Y0631511*
X0782308Y0631496*
X0782362Y0631484*
X0782416Y0631477*
X0782471Y0631473*
X0782526*
X0782581Y0631477*
X0782635Y0631484*
X0782689Y0631496*
X0782742Y0631511*
X0782794Y063153*
X0782844Y0631552*
X0782893Y0631578*
X0782939Y0631607*
X0782984Y063164*
X0783026Y0631675*
X0783065Y0631713*
X0783102Y0631754*
X0783136Y0631797*
X0783167Y0631843*
X0783194Y0631891*
X0783218Y063194*
X0783239Y0631991*
X0783256Y0632043*
X0783269Y0632097*
X0783279Y0632151*
X0783285Y0632206*
X0783287Y0632261*
X0821001Y0730447D02*
D01*
X0820999Y0730501*
X0820993Y0730556*
X0820983Y073061*
X082097Y0730664*
X0820953Y0730716*
X0820932Y0730767*
X0820908Y0730816*
X0820881Y0730864*
X082085Y073091*
X0820816Y0730953*
X0820779Y0730994*
X082074Y0731032*
X0820698Y0731067*
X0820653Y07311*
X0820607Y0731129*
X0820558Y0731155*
X0820508Y0731177*
X0820456Y0731196*
X0820403Y0731211*
X0820349Y0731223*
X0820295Y073123*
X082024Y0731234*
X0820185*
X082013Y073123*
X0820076Y0731223*
X0820022Y0731211*
X0819969Y0731196*
X0819917Y0731177*
X0819867Y0731155*
X0819819Y0731129*
X0819772Y07311*
X0819727Y0731067*
X0819685Y0731032*
X0819646Y0730994*
X0819609Y0730953*
X0819575Y073091*
X0819544Y0730864*
X0819517Y0730816*
X0819493Y0730767*
X0819472Y0730716*
X0819455Y0730664*
X0819442Y073061*
X0819432Y0730556*
X0819426Y0730501*
X0819425Y0730447*
X0819426Y0730392*
X0819432Y0730337*
X0819442Y0730283*
X0819455Y0730229*
X0819472Y0730177*
X0819493Y0730126*
X0819517Y0730077*
X0819544Y0730029*
X0819575Y0729983*
X0819609Y072994*
X0819646Y0729899*
X0819685Y0729861*
X0819727Y0729826*
X0819772Y0729793*
X0819819Y0729764*
X0819867Y0729738*
X0819917Y0729716*
X0819969Y0729697*
X0820022Y0729682*
X0820076Y072967*
X082013Y0729663*
X0820185Y0729659*
X082024*
X0820295Y0729663*
X0820349Y072967*
X0820403Y0729682*
X0820456Y0729697*
X0820508Y0729716*
X0820558Y0729738*
X0820607Y0729764*
X0820653Y0729793*
X0820698Y0729826*
X082074Y0729861*
X0820779Y0729899*
X0820816Y072994*
X082085Y0729983*
X0820881Y0730029*
X0820908Y0730077*
X0820932Y0730126*
X0820953Y0730177*
X082097Y0730229*
X0820983Y0730283*
X0820993Y0730337*
X0820999Y0730392*
X0821001Y0730447*
X0943178Y0709229D02*
D01*
X0943176Y0709283*
X094317Y0709338*
X094316Y0709392*
X0943147Y0709446*
X094313Y0709498*
X0943109Y0709549*
X0943085Y0709598*
X0943058Y0709646*
X0943027Y0709692*
X0942993Y0709735*
X0942956Y0709776*
X0942917Y0709814*
X0942875Y0709849*
X094283Y0709882*
X0942784Y0709911*
X0942735Y0709937*
X0942685Y0709959*
X0942633Y0709978*
X094258Y0709993*
X0942526Y0710005*
X0942472Y0710012*
X0942417Y0710016*
X0942362*
X0942307Y0710012*
X0942253Y0710005*
X0942199Y0709993*
X0942146Y0709978*
X0942094Y0709959*
X0942044Y0709937*
X0941996Y0709911*
X0941949Y0709882*
X0941904Y0709849*
X0941862Y0709814*
X0941823Y0709776*
X0941786Y0709735*
X0941752Y0709692*
X0941721Y0709646*
X0941694Y0709598*
X094167Y0709549*
X0941649Y0709498*
X0941632Y0709446*
X0941619Y0709392*
X0941609Y0709338*
X0941603Y0709283*
X0941602Y0709229*
X0941603Y0709174*
X0941609Y0709119*
X0941619Y0709065*
X0941632Y0709011*
X0941649Y0708959*
X094167Y0708908*
X0941694Y0708859*
X0941721Y0708811*
X0941752Y0708765*
X0941786Y0708722*
X0941823Y0708681*
X0941862Y0708643*
X0941904Y0708608*
X0941949Y0708575*
X0941996Y0708546*
X0942044Y070852*
X0942094Y0708498*
X0942146Y0708479*
X0942199Y0708464*
X0942253Y0708452*
X0942307Y0708445*
X0942362Y0708441*
X0942417*
X0942472Y0708445*
X0942526Y0708452*
X094258Y0708464*
X0942633Y0708479*
X0942685Y0708498*
X0942735Y070852*
X0942784Y0708546*
X094283Y0708575*
X0942875Y0708608*
X0942917Y0708643*
X0942956Y0708681*
X0942993Y0708722*
X0943027Y0708765*
X0943058Y0708811*
X0943085Y0708859*
X0943109Y0708908*
X094313Y0708959*
X0943147Y0709011*
X094316Y0709065*
X094317Y0709119*
X0943176Y0709174*
X0943178Y0709229*
G54D18*
X1284Y07072D02*
X1289D01*
X1284Y07128D02*
X1289D01*
X12053Y0854031D02*
Y0857969D01*
X0848272Y0916428D02*
Y0923928D01*
X0816272Y0916428D02*
Y0923928D01*
X1004961Y0910264D02*
Y0917764D01*
X0967461Y0910264D02*
Y0917764D01*
X12985Y0831D02*
X13D01*
Y083D02*
Y0831D01*
X12985Y0816D02*
X13D01*
Y0817*
X1265Y0816D02*
X12665D01*
X1265Y0831D02*
X12665D01*
X1265Y0816D02*
Y0831D01*
X13Y0817D02*
Y083D01*
X1277Y0816D02*
X1288D01*
X1277Y0831D02*
X1288D01*
X12675Y08185D02*
Y08285D01*
X0931Y0871D02*
X0937D01*
X09495Y0778131D02*
Y0782068D01*
X1182Y0858D02*
Y0934D01*
X113855Y0858D02*
X1182D01*
X113855D02*
Y0909799D01*
Y0934D02*
X1182D01*
X113855Y0909799D02*
Y0934D01*
X10292Y0779D02*
Y0785D01*
X10368Y0779D02*
Y0785D01*
X10002Y0804D02*
Y0809D01*
X10058Y0804D02*
Y0809D01*
X0798Y09306D02*
X0808D01*
X0798Y09006D02*
Y09306D01*
Y09006D02*
X0808D01*
Y09306*
X11745Y08558D02*
X11805D01*
X11745Y08482D02*
X11805D01*
X12432Y0725D02*
Y073D01*
X12488Y0725D02*
Y073D01*
X12482Y06965D02*
Y07015D01*
X12538Y06965D02*
Y07015D01*
X12287Y0712D02*
Y0718D01*
X12363Y0712D02*
Y0718D01*
X12688Y07105D02*
Y07165D01*
X12612Y07105D02*
Y07165D01*
X1228209Y0776528D02*
Y0782528D01*
X1220609Y0776528D02*
Y0782528D01*
X124002Y0776528D02*
Y0782528D01*
X1232421Y0776528D02*
Y0782528D01*
X12625Y06463D02*
X12685D01*
X12625Y06387D02*
X12685D01*
X12625Y06573D02*
X12685D01*
X12625Y06497D02*
X12685D01*
X1209Y07203D02*
X1214D01*
X1209Y07147D02*
X1214D01*
X10057Y0878D02*
Y0884D01*
X10133Y0878D02*
Y0884D01*
X10157Y08785D02*
Y08835D01*
X10213Y08785D02*
Y08835D01*
X12435Y08113D02*
X12495D01*
X12435Y08037D02*
X12495D01*
X08238Y08655D02*
Y08715D01*
X08162Y08655D02*
Y08715D01*
X08592Y08545D02*
Y08605D01*
X08668Y08545D02*
Y08605D01*
X09655Y05692D02*
X09715D01*
X09655Y05768D02*
X09715D01*
X09065Y08278D02*
X09115D01*
X09065Y08222D02*
X09115D01*
X09722Y08127D02*
Y08187D01*
X09646Y08127D02*
Y08187D01*
X09651Y08277D02*
Y08327D01*
X09707Y08277D02*
Y08327D01*
X09073Y0804D02*
Y0809D01*
X09017Y0804D02*
Y0809D01*
X09163Y0803D02*
Y0809D01*
X09087Y0803D02*
Y0809D01*
X09105Y08208D02*
X09165D01*
X09105Y08132D02*
X09165D01*
X08927Y0793D02*
Y0799D01*
X09003Y0793D02*
Y0799D01*
X10185Y0850031D02*
Y0853969D01*
X1272031Y0712D02*
X1275968D01*
X1220531Y0716D02*
X1224469D01*
X1286Y0680031D02*
Y0683968D01*
X12745Y0680031D02*
Y0683968D01*
X1233Y0743532D02*
Y0747469D01*
X1298032Y06915D02*
X1301968D01*
X1197532Y0737D02*
X1201468D01*
X08905Y0871D02*
X08965D01*
X09005D02*
X09065D01*
X09105D02*
X09165D01*
X0811732Y07656D02*
X0815668D01*
X1013Y0868532D02*
Y0872468D01*
X0660944Y0907D02*
X0664881D01*
X0681111D02*
X0685048D01*
X0701277D02*
X0705214D01*
X0721444D02*
X0725381D01*
X1067Y0919032D02*
Y0922968D01*
X1123Y0919032D02*
Y0922968D01*
X1067Y0910532D02*
Y0914468D01*
X1123Y0911032D02*
Y0914968D01*
X1209332Y07465D02*
X1213268D01*
X07379Y09314D02*
X07479D01*
X07379Y09014D02*
Y09314D01*
Y09014D02*
X07479D01*
Y09314*
X0790431Y09106D02*
X0794369D01*
X07661Y09305D02*
X07711D01*
X07661Y09249D02*
X07711D01*
X07798Y09318D02*
X07858D01*
X07798Y09242D02*
X07858D01*
X12567Y08275D02*
Y08325D01*
X12623Y08275D02*
Y08325D01*
Y0814D02*
Y0819D01*
X12567Y0814D02*
Y0819D01*
X10205Y08212D02*
X10265D01*
X10205Y08288D02*
X10265D01*
X10017Y0779D02*
Y0785D01*
X10093Y0779D02*
Y0785D01*
X09912Y0779D02*
Y0785D01*
X09988Y0779D02*
Y0785D01*
X10187Y0779D02*
Y0785D01*
X10263Y0779D02*
Y0785D01*
G54D19*
X1216626Y0741843D02*
X1232374D01*
X1216626Y0722157D02*
X1237886D01*
X1264626Y0686158D02*
X1280374D01*
X1259114Y0705842D02*
X1280374D01*
G54D20*
X0602Y0605D02*
X0606Y0609D01*
X0609*
X0602Y0577D02*
X0606Y0573D01*
X0609*
Y0609D02*
X0637D01*
Y0601D02*
Y0609D01*
X0609Y0573D02*
X0637D01*
Y0581*
X0602Y07625D02*
X0606Y07665D01*
X0609*
X0602Y07345D02*
X0606Y07305D01*
X0609*
Y07665D02*
X0637D01*
Y07585D02*
Y07665D01*
X0609Y07305D02*
X0637D01*
Y07385*
X0602Y071D02*
X0606Y0714D01*
X0609*
X0602Y0682D02*
X0606Y0678D01*
X0609*
Y0714D02*
X0637D01*
Y0706D02*
Y0714D01*
X0609Y0678D02*
X0637D01*
Y0686*
X0602Y06575D02*
X0606Y06615D01*
X0609*
X0602Y06295D02*
X0606Y06255D01*
X0609*
Y06615D02*
X0637D01*
Y06535D02*
Y06615D01*
X0609Y06255D02*
X0637D01*
Y06335*
G54D21*
X08982Y0588379D02*
X0900826D01*
Y0590741*
X0902991*
Y0601765*
X0900826D02*
X0902991D01*
X0900826D02*
Y0604127D01*
X08982D02*
X0900826D01*
X0816574Y0588379D02*
X08192D01*
X0816574D02*
Y0590741D01*
X0814409D02*
X0816574D01*
X0814409D02*
Y0601765D01*
X0816574*
Y0604127*
X08192*
X0760825Y0628621D02*
Y0631247D01*
Y0628621D02*
X0763187D01*
Y0626456D02*
Y0628621D01*
Y0626456D02*
X0774211D01*
Y0628621*
X0776573*
Y0631247*
X0760825Y0710247D02*
Y0712873D01*
X0763187*
Y0715038*
X0774211*
Y0712873D02*
Y0715038D01*
Y0712873D02*
X0776573D01*
Y0710247D02*
Y0712873D01*
X0898199Y0736373D02*
X0900825D01*
Y0738735*
X090299*
Y0749759*
X0900825D02*
X090299D01*
X0900825D02*
Y0752121D01*
X0898199D02*
X0900825D01*
X0816573Y0736373D02*
X0819199D01*
X0816573D02*
Y0738735D01*
X0814408D02*
X0816573D01*
X0814408D02*
Y0749759D01*
X0816573*
Y0752121*
X0819199*
X0964064Y0710243D02*
Y0712869D01*
X0961702D02*
X0964064D01*
X0961702D02*
Y0715034D01*
X0950678D02*
X0961702D01*
X0950678Y0712869D02*
Y0715034D01*
X0948316Y0712869D02*
X0950678D01*
X0948316Y0710243D02*
Y0712869D01*
X0964064Y0628617D02*
Y0631243D01*
X0961702Y0628617D02*
X0964064D01*
X0961702Y0626452D02*
Y0628617D01*
X0950678Y0626452D02*
X0961702D01*
X0950678D02*
Y0628617D01*
X0948316D02*
X0950678D01*
X0948316D02*
Y0631243D01*
G54D22*
X0754099Y0759113D02*
X0970635D01*
X0754099Y0581947D02*
X0970635D01*
Y0759113*
X0754099Y0581947D02*
Y0759113D01*
G54D23*
X129937Y0853384D02*
Y0857604D01*
G54D24*
X103285Y0791801D02*
X103235Y0791301D01*
Y0790302*
X103285Y0789802*
X1034849*
X1035349Y0790302*
Y0791301*
X1034849Y0791801*
X103235Y0792801D02*
Y07948D01*
X103285*
X1034849Y0792801*
X1035349*
Y0797799D02*
Y07958D01*
X103335Y0797799*
X103285*
X103235Y0797299*
Y07963*
X103285Y07958*
X102255Y0791901D02*
X102205Y0791401D01*
Y0790402*
X102255Y0789902*
X1024549*
X1025049Y0790402*
Y0791401*
X1024549Y0791901*
X102205Y0792901D02*
Y07949D01*
X102255*
X1024549Y0792901*
X1025049*
X102255Y07959D02*
X102205Y07964D01*
Y07974*
X102255Y0797899*
X102305*
X102355Y07974*
Y07969*
Y07974*
X102405Y0797899*
X1024549*
X1025049Y07974*
Y07964*
X1024549Y07959*
X0977801Y078225D02*
X0977302Y078275D01*
X0976302*
X0975802Y078225*
Y0780251*
X0976302Y0779751*
X0977302*
X0977801Y0780251*
X0978801Y078275D02*
X09808D01*
Y078225*
X0978801Y0780251*
Y0779751*
X09833D02*
Y078275D01*
X09818Y078125*
X0983799*
X0999201Y079405D02*
X0998701Y079455D01*
X0997702*
X0997202Y079405*
Y0792051*
X0997702Y0791551*
X0998701*
X0999201Y0792051*
X1000201Y079455D02*
X10022D01*
Y079405*
X1000201Y0792051*
Y0791551*
X1005199Y079455D02*
X10032D01*
Y079305*
X10042Y079355*
X10047*
X1005199Y079305*
Y0792051*
X10047Y0791551*
X10037*
X10032Y0792051*
X0994745Y0821291D02*
X0994245Y0820791D01*
Y0819791*
X0994745Y0819291*
X0996744*
X0997244Y0819791*
Y0820791*
X0996744Y0821291*
X0994245Y082229D02*
Y082429D01*
X0994745*
X0996744Y082229*
X0997244*
X0994245Y0827289D02*
X0994745Y0826289D01*
X0995745Y0825289*
X0996744*
X0997244Y0825789*
Y0826789*
X0996744Y0827289*
X0996244*
X0995745Y0826789*
Y0825289*
X1000158Y0821291D02*
X0999658Y0820791D01*
Y0819791*
X1000158Y0819291*
X1002158*
X1002658Y0819791*
Y0820791*
X1002158Y0821291*
X0999658Y082229D02*
Y082429D01*
X1000158*
X1002158Y082229*
X1002658*
X0999658Y0825289D02*
Y0827289D01*
X1000158*
X1002158Y0825289*
X1002658*
X1005965Y0821192D02*
X1005466Y0820692D01*
Y0819693*
X1005965Y0819193*
X1007965*
X1008465Y0819693*
Y0820692*
X1007965Y0821192*
X1005466Y0822192D02*
Y0824191D01*
X1005965*
X1007965Y0822192*
X1008465*
X1005965Y0825191D02*
X1005466Y0825691D01*
Y082669*
X1005965Y082719*
X1006465*
X1006965Y082669*
X1007465Y082719*
X1007965*
X1008465Y082669*
Y0825691*
X1007965Y0825191*
X1007465*
X1006965Y0825691*
X1006465Y0825191*
X1005965*
X1006965Y0825691D02*
Y082669D01*
X1011576Y0821192D02*
X1011076Y0820692D01*
Y0819693*
X1011576Y0819193*
X1013575*
X1014075Y0819693*
Y0820692*
X1013575Y0821192*
X1011076Y0822192D02*
Y0824191D01*
X1011576*
X1013575Y0822192*
X1014075*
X1013575Y0825191D02*
X1014075Y0825691D01*
Y082669*
X1013575Y082719*
X1011576*
X1011076Y082669*
Y0825691*
X1011576Y0825191*
X1012075*
X1012575Y0825691*
Y082719*
X1032934Y0823456D02*
X1032434Y0822956D01*
Y0821957*
X1032934Y0821457*
X1034933*
X1035433Y0821957*
Y0822956*
X1034933Y0823456*
X1032934Y0824456D02*
X1032434Y0824956D01*
Y0825955*
X1032934Y0826455*
X1033434*
X1033934Y0825955*
X1034433Y0826455*
X1034933*
X1035433Y0825955*
Y0824956*
X1034933Y0824456*
X1034433*
X1033934Y0824956*
X1033434Y0824456*
X1032934*
X1033934Y0824956D02*
Y0825955D01*
X1032934Y0827455D02*
X1032434Y0827955D01*
Y0828954*
X1032934Y0829454*
X1034933*
X1035433Y0828954*
Y0827955*
X1034933Y0827455*
X1032934*
X1037954Y0823456D02*
X1037454Y0822956D01*
Y0821957*
X1037954Y0821457*
X1039953*
X1040453Y0821957*
Y0822956*
X1039953Y0823456*
X1037954Y0824456D02*
X1037454Y0824956D01*
Y0825955*
X1037954Y0826455*
X1038453*
X1038953Y0825955*
X1039453Y0826455*
X1039953*
X1040453Y0825955*
Y0824956*
X1039953Y0824456*
X1039453*
X1038953Y0824956*
X1038453Y0824456*
X1037954*
X1038953Y0824956D02*
Y0825955D01*
X1040453Y0827455D02*
Y0828454D01*
Y0827955*
X1037454*
X1037954Y0827455*
X1042875Y0822964D02*
X1042375Y0822464D01*
Y0821464*
X1042875Y0820965*
X1044874*
X1045374Y0821464*
Y0822464*
X1044874Y0822964*
X1042875Y0823964D02*
X1042375Y0824463D01*
Y0825463*
X1042875Y0825963*
X1043375*
X1043874Y0825463*
X1044374Y0825963*
X1044874*
X1045374Y0825463*
Y0824463*
X1044874Y0823964*
X1044374*
X1043874Y0824463*
X1043375Y0823964*
X1042875*
X1043874Y0824463D02*
Y0825463D01*
X1045374Y0828962D02*
Y0826963D01*
X1043375Y0828962*
X1042875*
X1042375Y0828462*
Y0827462*
X1042875Y0826963*
X1047796Y0818929D02*
X1047296Y0818429D01*
Y0817429*
X1047796Y0816929*
X1049795*
X1050295Y0817429*
Y0818429*
X1049795Y0818929*
X1047796Y0819928D02*
X1047296Y0820428D01*
Y0821428*
X1047796Y0821928*
X1048296*
X1048796Y0821428*
X1049296Y0821928*
X1049795*
X1050295Y0821428*
Y0820428*
X1049795Y0819928*
X1049296*
X1048796Y0820428*
X1048296Y0819928*
X1047796*
X1048796Y0820428D02*
Y0821428D01*
X1047796Y0822927D02*
X1047296Y0823427D01*
Y0824427*
X1047796Y0824926*
X1048296*
X1048796Y0824427*
Y0823927*
Y0824427*
X1049296Y0824926*
X1049795*
X1050295Y0824427*
Y0823427*
X1049795Y0822927*
X1019099Y0834499D02*
X10186Y0834999D01*
X10176*
X10171Y0834499*
Y08325*
X10176Y0832*
X10186*
X1019099Y08325*
X1020099Y0834499D02*
X1020599Y0834999D01*
X1021599*
X1022098Y0834499*
Y0833999*
X1021599Y08335*
X1022098Y0833*
Y08325*
X1021599Y0832*
X1020599*
X1020099Y08325*
Y0833*
X1020599Y08335*
X1020099Y0833999*
Y0834499*
X1020599Y08335D02*
X1021599D01*
X1024598Y0832D02*
Y0834999D01*
X1023098Y08335*
X1025097*
X1264501Y080805D02*
X1264001Y080855D01*
X1263002*
X1262502Y080805*
Y0806051*
X1263002Y0805551*
X1264001*
X1264501Y0806051*
X1265501Y080805D02*
X1266001Y080855D01*
X1267*
X12675Y080805*
Y080755*
X1267Y080705*
X12675Y080655*
Y0806051*
X1267Y0805551*
X1266001*
X1265501Y0806051*
Y080655*
X1266001Y080705*
X1265501Y080755*
Y080805*
X1266001Y080705D02*
X1267D01*
X1270499Y080855D02*
X12685D01*
Y080705*
X12695Y080755*
X127*
X1270499Y080705*
Y0806051*
X127Y0805551*
X1269*
X12685Y0806051*
X1259601Y084035D02*
X1259101Y084085D01*
X1258102*
X1257602Y084035*
Y0838351*
X1258102Y0837851*
X1259101*
X1259601Y0838351*
X1260601Y084035D02*
X1261101Y084085D01*
X1262101*
X12626Y084035*
Y083985*
X1262101Y083935*
X12626Y083885*
Y0838351*
X1262101Y0837851*
X1261101*
X1260601Y0838351*
Y083885*
X1261101Y083935*
X1260601Y083985*
Y084035*
X1261101Y083935D02*
X1262101D01*
X1265599Y084085D02*
X12646Y084035D01*
X12636Y083935*
Y0838351*
X12641Y0837851*
X12651*
X1265599Y0838351*
Y083885*
X12651Y083935*
X12636*
X079305Y0924751D02*
X079255Y0924251D01*
Y0923252*
X079305Y0922752*
X0795049*
X0795549Y0923252*
Y0924251*
X0795049Y0924751*
Y0925751D02*
X0795549Y0926251D01*
Y092725*
X0795049Y092775*
X079305*
X079255Y092725*
Y0926251*
X079305Y0925751*
X079355*
X079405Y0926251*
Y092775*
X0795549Y092875D02*
Y0929749D01*
Y092925*
X079255*
X079305Y092875*
X0751601Y092835D02*
X0751101Y092885D01*
X0750102*
X0749602Y092835*
Y0926351*
X0750102Y0925851*
X0751101*
X0751601Y0926351*
X0752601D02*
X0753101Y0925851D01*
X0754101*
X07546Y0926351*
Y092835*
X0754101Y092885*
X0753101*
X0752601Y092835*
Y092785*
X0753101Y092735*
X07546*
X0757599Y0925851D02*
X07556D01*
X0757599Y092785*
Y092835*
X0757099Y092885*
X07561*
X07556Y092835*
X0872949Y0777502D02*
X086995D01*
Y0779002*
X087045Y0779501*
X087145*
X087195Y0779002*
Y0777502*
Y0778502D02*
X0872949Y0779501D01*
X087045Y0780501D02*
X086995Y0781001D01*
Y0782*
X087045Y07825*
X087095*
X087145Y0782*
Y0781501*
Y0782*
X087195Y07825*
X0872449*
X0872949Y0782*
Y0781001*
X0872449Y0780501*
X086995Y0785499D02*
X087045Y07845D01*
X087145Y07835*
X0872449*
X0872949Y0784*
Y0785*
X0872449Y0785499*
X087195*
X087145Y0785*
Y07835*
X0898002Y0841751D02*
Y084475D01*
X0899502*
X0900001Y084425*
Y084325*
X0899502Y084275*
X0898002*
X0899002D02*
X0900001Y0841751D01*
X0901001Y084425D02*
X0901501Y084475D01*
X0902501*
X0903Y084425*
Y084375*
X0902501Y084325*
X0902001*
X0902501*
X0903Y084275*
Y0842251*
X0902501Y0841751*
X0901501*
X0901001Y0842251*
X0904Y084475D02*
X0905999D01*
Y084425*
X0904Y0842251*
Y0841751*
X0882202Y0841851D02*
Y084485D01*
X0883702*
X0884201Y084435*
Y084335*
X0883702Y084285*
X0882202*
X0883202D02*
X0884201Y0841851D01*
X0885201Y084435D02*
X0885701Y084485D01*
X0886701*
X08872Y084435*
Y084385*
X0886701Y084335*
X0886201*
X0886701*
X08872Y084285*
Y0842351*
X0886701Y0841851*
X0885701*
X0885201Y0842351*
X08882Y084435D02*
X08887Y084485D01*
X0889699*
X0890199Y084435*
Y084385*
X0889699Y084335*
X0890199Y084285*
Y0842351*
X0889699Y0841851*
X08887*
X08882Y0842351*
Y084285*
X08887Y084335*
X08882Y084385*
Y084435*
X08887Y084335D02*
X0889699D01*
X0879949Y0777602D02*
X087695D01*
Y0779102*
X087745Y0779601*
X087845*
X087895Y0779102*
Y0777602*
Y0778602D02*
X0879949Y0779601D01*
X087745Y0780601D02*
X087695Y0781101D01*
Y07821*
X087745Y07826*
X087795*
X087845Y07821*
Y0781601*
Y07821*
X087895Y07826*
X0879449*
X0879949Y07821*
Y0781101*
X0879449Y0780601*
Y07836D02*
X0879949Y07841D01*
Y07851*
X0879449Y0785599*
X087745*
X087695Y07851*
Y07841*
X087745Y07836*
X087795*
X087845Y07841*
Y0785599*
X0886849Y0777502D02*
X088385D01*
Y0779002*
X088435Y0779501*
X088535*
X088585Y0779002*
Y0777502*
Y0778502D02*
X0886849Y0779501D01*
Y0782D02*
X088385D01*
X088535Y0780501*
Y07825*
X088435Y07835D02*
X088385Y0784D01*
Y0785*
X088435Y0785499*
X0886349*
X0886849Y0785*
Y0784*
X0886349Y07835*
X088435*
X0893449Y0777552D02*
X089045D01*
Y0779051*
X089095Y0779551*
X089195*
X089245Y0779051*
Y0777552*
Y0778551D02*
X0893449Y0779551D01*
Y078205D02*
X089045D01*
X089195Y0780551*
Y078255*
X0893449Y078355D02*
Y0784549D01*
Y078405*
X089045*
X089095Y078355*
X0943702Y0769851D02*
Y077285D01*
X0945201*
X0945701Y077235*
Y077135*
X0945201Y077085*
X0943702*
X0944702D02*
X0945701Y0769851D01*
X0948201D02*
Y077285D01*
X0946701Y077135*
X09487*
X0951699Y0769851D02*
X09497D01*
X0951699Y077185*
Y077235*
X09512Y077285*
X09502*
X09497Y077235*
X0788601Y0917101D02*
Y09201D01*
X0790101*
X0790601Y09196*
Y09186*
X0790101Y09181*
X0788601*
X0789601D02*
X0790601Y0917101D01*
X07931D02*
Y09201D01*
X07916Y09186*
X07936*
X0794599Y09196D02*
X0795099Y09201D01*
X0796099*
X0796599Y09196*
Y09191*
X0796099Y09186*
X0795599*
X0796099*
X0796599Y09181*
Y09176*
X0796099Y0917101*
X0795099*
X0794599Y09176*
X075315Y0902977D02*
X0755649D01*
X0756149Y0903477*
Y0904476*
X0755649Y0904976*
X075315*
X0756149Y0905976D02*
Y0906975D01*
Y0906476*
X075315*
X075365Y0905976*
X075315Y0910474D02*
X075365Y0909475D01*
X075465Y0908475*
X0755649*
X0756149Y0908975*
Y0909975*
X0755649Y0910474*
X075515*
X075465Y0909975*
Y0908475*
X081115Y0908101D02*
Y0907102D01*
Y0907602*
X0813649*
X0814149Y0907102*
Y0906602*
X0813649Y0906102*
X0814149Y0909101D02*
X081115D01*
Y09106*
X081165Y09111*
X081265*
X081315Y09106*
Y0909101*
X0814149Y0914099D02*
Y09121D01*
X081215Y0914099*
X081165*
X081115Y0913599*
Y09126*
X081165Y09121*
X073205Y0905051D02*
Y0904051D01*
Y0904551*
X0734549*
X0735049Y0904051*
Y0903551*
X0734549Y0903052*
X0735049Y0906051D02*
X073205D01*
Y090755*
X073255Y090805*
X073355*
X073405Y090755*
Y0906051*
X0735049Y090905D02*
Y0910049D01*
Y090955*
X073205*
X073255Y090905*
X0852551Y091925D02*
X0851551D01*
X0852051*
Y0916751*
X0851551Y0916251*
X0851051*
X0850551Y0916751*
X085505Y0916251D02*
Y091925D01*
X085355Y091775*
X085555*
X12125Y0752953D02*
X1209501D01*
Y0754452*
X1210001Y0754952*
X1211001*
X12115Y0754452*
Y0752953*
Y0753952D02*
X12125Y0754952D01*
X1209501Y0757951D02*
Y0755952D01*
X1211001*
X1210501Y0756952*
Y0757451*
X1211001Y0757951*
X1212*
X12125Y0757451*
Y0756452*
X1212Y0755952*
X1294201Y083955D02*
X12962Y0836551D01*
Y083955D02*
X1294201Y0836551D01*
X12972D02*
X12982D01*
X12977*
Y083955*
X12972Y083905*
X0957877Y078935D02*
Y0786851D01*
X0958377Y0786351*
X0959376*
X0959876Y0786851*
Y078935*
X0960876Y0786351D02*
X0961876D01*
X0961376*
Y078935*
X0960876Y078885*
X0963375D02*
X0963875Y078935D01*
X0964875*
X0965374Y078885*
Y078835*
X0964875Y078785*
X0964375*
X0964875*
X0965374Y078735*
Y0786851*
X0964875Y0786351*
X0963875*
X0963375Y0786851*
X08734Y0836399D02*
Y08339D01*
X08739Y08334*
X0874899*
X0875399Y08339*
Y0836399*
X0876399Y08334D02*
X0877399D01*
X0876899*
Y0836399*
X0876399Y0835899*
X0880898Y08334D02*
X0878898D01*
X0880898Y0835399*
Y0835899*
X0880398Y0836399*
X0879398*
X0878898Y0835899*
X0914927Y084245D02*
Y0839951D01*
X0915426Y0839451*
X0916426*
X0916926Y0839951*
Y084245*
X0917926Y0839451D02*
X0918925D01*
X0918425*
Y084245*
X0917926Y084195*
X0920425Y0839451D02*
X0921424D01*
X0920925*
Y084245*
X0920425Y084195*
X1164277Y077485D02*
Y0772351D01*
X1164777Y0771851*
X1165776*
X1166276Y0772351*
Y077485*
X1167276Y0771851D02*
X1168276D01*
X1167776*
Y077485*
X1167276Y077435*
X1169775D02*
X1170275Y077485D01*
X1171275*
X1171774Y077435*
Y0772351*
X1171275Y0771851*
X1170275*
X1169775Y0772351*
Y077435*
X0837402Y0874653D02*
Y0872153D01*
X0837901Y0871653*
X0838901*
X0839401Y0872153*
Y0874653*
X0840401Y0872153D02*
X08409Y0871653D01*
X08419*
X08424Y0872153*
Y0874153*
X08419Y0874653*
X08409*
X0840401Y0874153*
Y0873653*
X08409Y0873153*
X08424*
X12359Y0841899D02*
Y08394D01*
X12364Y08389*
X1237399*
X1237899Y08394*
Y0841899*
X1238899Y0841399D02*
X1239399Y0841899D01*
X1240399*
X1240898Y0841399*
Y0840899*
X1240399Y0840399*
X1240898Y08399*
Y08394*
X1240399Y08389*
X1239399*
X1238899Y08394*
Y08399*
X1239399Y0840399*
X1238899Y0840899*
Y0841399*
X1239399Y0840399D02*
X1240399D01*
X0983151Y086375D02*
Y0861251D01*
X0983651Y0860751*
X0984651*
X0985151Y0861251*
Y086375*
X098815D02*
X098715Y086325D01*
X098615Y086225*
Y0861251*
X098665Y0860751*
X098765*
X098815Y0861251*
Y086175*
X098765Y086225*
X098615*
X0861951Y092555D02*
Y0923051D01*
X0862451Y0922551*
X0863451*
X0863951Y0923051*
Y092555*
X086695D02*
X086495D01*
Y092405*
X086595Y092455*
X086645*
X086695Y092405*
Y0923051*
X086645Y0922551*
X086545*
X086495Y0923051*
X1200351Y072645D02*
Y0723951D01*
X1200851Y0723451*
X1201851*
X1202351Y0723951*
Y072645*
X120535Y0723451D02*
X120335D01*
X120535Y072545*
Y072595*
X120485Y072645*
X120385*
X120335Y072595*
X1255118Y071107D02*
Y0708571D01*
X1255618Y0708071*
X1256618*
X1257117Y0708571*
Y071107*
X1258117Y0708071D02*
X1259117D01*
X1258617*
Y071107*
X1258117Y071057*
X1140051Y085275D02*
X1139551Y085325D01*
X1138552*
X1138052Y085275*
Y085225*
X1138552Y085175*
X1139551*
X1140051Y085125*
Y0850751*
X1139551Y0850251*
X1138552*
X1138052Y0850751*
X1141051Y085325D02*
Y0850251D01*
X114205Y085125*
X114305Y0850251*
Y085325*
X114405Y0850251D02*
X1145049D01*
X114455*
Y085325*
X114405Y085275*
X1094199Y0932599D02*
X1093699Y0933099D01*
X10927*
X10922Y0932599*
Y0932099*
X10927Y09316*
X1093699*
X1094199Y09311*
Y09306*
X1093699Y09301*
X10927*
X10922Y09306*
X1097198Y0933099D02*
X1096199Y0932599D01*
X1095199Y09316*
Y09306*
X1095699Y09301*
X1096699*
X1097198Y09306*
Y09311*
X1096699Y09316*
X1095199*
X1041699Y0932599D02*
X1041199Y0933099D01*
X10402*
X10397Y0932599*
Y0932099*
X10402Y09316*
X1041199*
X1041699Y09311*
Y09306*
X1041199Y09301*
X10402*
X10397Y09306*
X1044698Y0933099D02*
X1042699D01*
Y09316*
X1043699Y0932099*
X1044199*
X1044698Y09316*
Y09306*
X1044199Y09301*
X1043199*
X1042699Y09306*
X1117902Y0901551D02*
Y090455D01*
X1119401*
X1119901Y090405*
Y090305*
X1119401Y090255*
X1117902*
X1118902D02*
X1119901Y0901551D01*
X1120901Y090405D02*
X1121401Y090455D01*
X11224*
X11229Y090405*
Y090355*
X11224Y090305*
X1121901*
X11224*
X11229Y090255*
Y0902051*
X11224Y0901551*
X1121401*
X1120901Y0902051*
X1125899Y090455D02*
X11239D01*
Y090305*
X11249Y090355*
X1125399*
X1125899Y090305*
Y0902051*
X1125399Y0901551*
X11244*
X11239Y0902051*
X1062402Y0902851D02*
Y090585D01*
X1063902*
X1064401Y090535*
Y090435*
X1063902Y090385*
X1062402*
X1063402D02*
X1064401Y0902851D01*
X1065401Y090535D02*
X1065901Y090585D01*
X1066901*
X10674Y090535*
Y090485*
X1066901Y090435*
X1066401*
X1066901*
X10674Y090385*
Y0903351*
X1066901Y0902851*
X1065901*
X1065401Y0903351*
X1069899Y0902851D02*
Y090585D01*
X10684Y090435*
X1070399*
X1119Y09267D02*
Y0929699D01*
X11205*
X1120999Y0929199*
Y0928199*
X11205Y09277*
X1119*
X112D02*
X1120999Y09267D01*
X1121999Y0929199D02*
X1122499Y0929699D01*
X1123499*
X1123998Y0929199*
Y0928699*
X1123499Y0928199*
X1122999*
X1123499*
X1123998Y09277*
Y09272*
X1123499Y09267*
X1122499*
X1121999Y09272*
X1124998Y0929199D02*
X1125498Y0929699D01*
X1126498*
X1126997Y0929199*
Y0928699*
X1126498Y0928199*
X1125998*
X1126498*
X1126997Y09277*
Y09272*
X1126498Y09267*
X1125498*
X1124998Y09272*
X1063Y09267D02*
Y0929699D01*
X1064499*
X1064999Y0929199*
Y0928199*
X1064499Y09277*
X1063*
X1064D02*
X1064999Y09267D01*
X1065999Y0929199D02*
X1066499Y0929699D01*
X1067499*
X1067998Y0929199*
Y0928699*
X1067499Y0928199*
X1066999*
X1067499*
X1067998Y09277*
Y09272*
X1067499Y09267*
X1066499*
X1065999Y09272*
X1070997Y09267D02*
X1068998D01*
X1070997Y0928699*
Y0929199*
X1070498Y0929699*
X1069498*
X1068998Y0929199*
X0718849Y0901752D02*
X071585D01*
Y0903251*
X071635Y0903751*
X071735*
X071785Y0903251*
Y0901752*
Y0902751D02*
X0718849Y0903751D01*
X071635Y0904751D02*
X071585Y0905251D01*
Y090625*
X071635Y090675*
X071685*
X071735Y090625*
Y090575*
Y090625*
X071785Y090675*
X0718349*
X0718849Y090625*
Y0905251*
X0718349Y0904751*
X0718849Y090775D02*
Y0908749D01*
Y090825*
X071585*
X071635Y090775*
X0698349Y0900802D02*
X069535D01*
Y0902302*
X069585Y0902801*
X069685*
X069735Y0902302*
Y0900802*
Y0901802D02*
X0698349Y0902801D01*
X069585Y0903801D02*
X069535Y0904301D01*
Y0905301*
X069585Y09058*
X069635*
X069685Y0905301*
Y0904801*
Y0905301*
X069735Y09058*
X0697849*
X0698349Y0905301*
Y0904301*
X0697849Y0903801*
X069585Y09068D02*
X069535Y09073D01*
Y09083*
X069585Y0908799*
X0697849*
X0698349Y09083*
Y09073*
X0697849Y09068*
X069585*
X0677949Y0900202D02*
X067495D01*
Y0901702*
X067545Y0902201*
X067645*
X067695Y0901702*
Y0900202*
Y0901202D02*
X0677949Y0902201D01*
Y09052D02*
Y0903201D01*
X067595Y09052*
X067545*
X067495Y09047*
Y0903701*
X067545Y0903201*
X0677449Y09062D02*
X0677949Y09067D01*
Y0907699*
X0677449Y0908199*
X067545*
X067495Y0907699*
Y09067*
X067545Y09062*
X067595*
X067645Y09067*
Y0908199*
X0657849Y0900202D02*
X065485D01*
Y0901702*
X065535Y0902201*
X065635*
X065685Y0901702*
Y0900202*
Y0901202D02*
X0657849Y0902201D01*
Y09052D02*
Y0903201D01*
X065585Y09052*
X065535*
X065485Y09047*
Y0903701*
X065535Y0903201*
Y09062D02*
X065485Y09067D01*
Y0907699*
X065535Y0908199*
X065585*
X065635Y0907699*
X065685Y0908199*
X0657349*
X0657849Y0907699*
Y09067*
X0657349Y09062*
X065685*
X065635Y09067*
X065585Y09062*
X065535*
X065635Y09067D02*
Y0907699D01*
X1019702Y0868251D02*
Y087125D01*
X1021202*
X1021701Y087075*
Y086975*
X1021202Y086925*
X1019702*
X1020702D02*
X1021701Y0868251D01*
X10247D02*
X1022701D01*
X10247Y087025*
Y087075*
X1024201Y087125*
X1023201*
X1022701Y087075*
X10257Y087125D02*
X1027699D01*
Y087075*
X10257Y0868751*
Y0868251*
X0969549Y0860802D02*
X096655D01*
Y0862302*
X096705Y0862801*
X096805*
X096855Y0862302*
Y0860802*
Y0861802D02*
X0969549Y0862801D01*
Y08658D02*
Y0863801D01*
X096755Y08658*
X096705*
X096655Y08653*
Y0864301*
X096705Y0863801*
X096655Y0868799D02*
X096705Y08678D01*
X096805Y08668*
X0969049*
X0969549Y08673*
Y0868299*
X0969049Y0868799*
X096855*
X096805Y0868299*
Y08668*
X0962202Y0889451D02*
Y089245D01*
X0963702*
X0964201Y089195*
Y089095*
X0963702Y089045*
X0962202*
X0963202D02*
X0964201Y0889451D01*
X09672D02*
X0965201D01*
X09672Y089145*
Y089195*
X09667Y089245*
X0965701*
X0965201Y089195*
X0970199Y089245D02*
X09682D01*
Y089095*
X09692Y089145*
X0969699*
X0970199Y089095*
Y0889951*
X0969699Y0889451*
X09687*
X09682Y0889951*
X0901149Y0552602D02*
X089815D01*
Y0554102*
X089865Y0554601*
X089965*
X090015Y0554102*
Y0552602*
Y0553602D02*
X0901149Y0554601D01*
Y05576D02*
Y0555601D01*
X089915Y05576*
X089865*
X089815Y05571*
Y0556101*
X089865Y0555601*
X0901149Y05601D02*
X089815D01*
X089965Y05586*
Y0560599*
X0841949Y0552902D02*
X083895D01*
Y0554401*
X083945Y0554901*
X084045*
X084095Y0554401*
Y0552902*
Y0553902D02*
X0841949Y0554901D01*
Y05579D02*
Y0555901D01*
X083995Y05579*
X083945*
X083895Y0557401*
Y0556401*
X083945Y0555901*
Y05589D02*
X083895Y05594D01*
Y0560399*
X083945Y0560899*
X083995*
X084045Y0560399*
Y05599*
Y0560399*
X084095Y0560899*
X0841449*
X0841949Y0560399*
Y05594*
X0841449Y05589*
X0797302Y0763651D02*
Y076665D01*
X0798802*
X0799301Y076615*
Y076515*
X0798802Y076465*
X0797302*
X0798302D02*
X0799301Y0763651D01*
X08023D02*
X0800301D01*
X08023Y076565*
Y076615*
X0801801Y076665*
X0800801*
X0800301Y076615*
X0805299Y0763651D02*
X08033D01*
X0805299Y076565*
Y076615*
X0804799Y076665*
X08038*
X08033Y076615*
X0936149Y0852352D02*
X093315D01*
Y0853851*
X093365Y0854351*
X093465*
X093515Y0853851*
Y0852352*
Y0853351D02*
X0936149Y0854351D01*
Y085735D02*
Y0855351D01*
X093415Y085735*
X093365*
X093315Y085685*
Y0855851*
X093365Y0855351*
X0936149Y085835D02*
Y0859349D01*
Y085885*
X093315*
X093365Y085835*
X0915849Y0851402D02*
X091285D01*
Y0852901*
X091335Y0853401*
X091435*
X091485Y0852901*
Y0851402*
Y0852402D02*
X0915849Y0853401D01*
Y08564D02*
Y0854401D01*
X091385Y08564*
X091335*
X091285Y08559*
Y0854901*
X091335Y0854401*
Y08574D02*
X091285Y08579D01*
Y0858899*
X091335Y0859399*
X0915349*
X0915849Y0858899*
Y08579*
X0915349Y08574*
X091335*
X0905649Y0851777D02*
X090265D01*
Y0853276*
X090315Y0853776*
X090415*
X090465Y0853276*
Y0851777*
Y0852777D02*
X0905649Y0853776D01*
Y0854776D02*
Y0855776D01*
Y0855276*
X090265*
X090315Y0854776*
X0905149Y0857275D02*
X0905649Y0857775D01*
Y0858775*
X0905149Y0859274*
X090315*
X090265Y0858775*
Y0857775*
X090315Y0857275*
X090365*
X090415Y0857775*
Y0859274*
X0896249Y0851777D02*
X089325D01*
Y0853276*
X089375Y0853776*
X089475*
X089525Y0853276*
Y0851777*
Y0852777D02*
X0896249Y0853776D01*
Y0854776D02*
Y0855776D01*
Y0855276*
X089325*
X089375Y0854776*
Y0857275D02*
X089325Y0857775D01*
Y0858775*
X089375Y0859274*
X089425*
X089475Y0858775*
X089525Y0859274*
X0895749*
X0896249Y0858775*
Y0857775*
X0895749Y0857275*
X089525*
X089475Y0857775*
X089425Y0857275*
X089375*
X089475Y0857775D02*
Y0858775D01*
X1200689Y0746555D02*
X119769D01*
Y0748055*
X119819Y0748555*
X1199189*
X1199689Y0748055*
Y0746555*
Y0747555D02*
X1200689Y0748555D01*
X1200189Y0749554D02*
X1200689Y0750054D01*
Y0751054*
X1200189Y0751553*
X119819*
X119769Y0751054*
Y0750054*
X119819Y0749554*
X119869*
X1199189Y0750054*
Y0751553*
X1306988Y0687598D02*
X1303989D01*
Y0689098*
X1304489Y0689598*
X1305489*
X1305989Y0689098*
Y0687598*
Y0688598D02*
X1306988Y0689598D01*
X1304489Y0690597D02*
X1303989Y0691097D01*
Y0692097*
X1304489Y0692597*
X1304989*
X1305489Y0692097*
X1305989Y0692597*
X1306488*
X1306988Y0692097*
Y0691097*
X1306488Y0690597*
X1305989*
X1305489Y0691097*
X1304989Y0690597*
X1304489*
X1305489Y0691097D02*
Y0692097D01*
X1217323Y0744488D02*
Y0747487D01*
X1218822*
X1219322Y0746987*
Y0745988*
X1218822Y0745488*
X1217323*
X1218322D02*
X1219322Y0744488D01*
X1220322Y0747487D02*
X1222321D01*
Y0746987*
X1220322Y0744988*
Y0744488*
X129311Y0680413D02*
Y0683412D01*
X129461*
X129511Y0682913*
Y0681913*
X129461Y0681413*
X129311*
X129411D02*
X129511Y0680413D01*
X1298109Y0683412D02*
X1297109Y0682913D01*
X1296109Y0681913*
Y0680913*
X1296609Y0680413*
X1297609*
X1298109Y0680913*
Y0681413*
X1297609Y0681913*
X1296109*
X1300591Y0680217D02*
Y0683216D01*
X130209*
X130259Y0682716*
Y0681716*
X130209Y0681216*
X1300591*
X130159D02*
X130259Y0680217D01*
X1305089D02*
Y0683216D01*
X130359Y0681716*
X1305589*
X121998Y0706201D02*
Y07092D01*
X122148*
X122198Y07087*
Y07077*
X122148Y07072*
X121998*
X122098D02*
X122198Y0706201D01*
X1222979Y07087D02*
X1223479Y07092D01*
X1224479*
X1224979Y07087*
Y07082*
X1224479Y07077*
X1223979*
X1224479*
X1224979Y07072*
Y0706701*
X1224479Y0706201*
X1223479*
X1222979Y0706701*
X1275591Y0719095D02*
X1272591D01*
Y0720594*
X1273091Y0721094*
X1274091*
X1274591Y0720594*
Y0719095*
Y0720094D02*
X1275591Y0721094D01*
Y0724093D02*
Y0722093D01*
X1273591Y0724093*
X1273091*
X1272591Y0723593*
Y0722593*
X1273091Y0722093*
X10145Y08577D02*
Y0860699D01*
X1016*
X1016499Y0860199*
Y08592*
X1016Y08587*
X10145*
X10155D02*
X1016499Y08577D01*
X1017499D02*
X1018499D01*
X1017999*
Y0860699*
X1017499Y0860199*
X0777821Y0525673D02*
Y0528672D01*
X0779321*
X0779821Y0528172*
Y0527173*
X0779321Y0526673*
X0777821*
X078282Y0525673D02*
X078082D01*
X078282Y0527673*
Y0528172*
X078232Y0528672*
X078132*
X078082Y0528172*
X07547Y07623D02*
Y0765299D01*
X07562*
X0756699Y0764799*
Y0763799*
X07562Y07633*
X07547*
X0757699Y07623D02*
X0758699D01*
X0758199*
Y0765299*
X0757699Y0764799*
X1285651Y079435D02*
Y0791351D01*
X1287651*
X129065D02*
X128865D01*
X129065Y079335*
Y079385*
X129015Y079435*
X128915*
X128865Y079385*
X1196401Y069035D02*
Y0687351D01*
X11984*
X11994D02*
X12004D01*
X11999*
Y069035*
X11994Y068985*
X1012651Y092705D02*
X1011651D01*
X1012151*
Y0924551*
X1011651Y0924051*
X1011151*
X1010651Y0924551*
X101365Y092655D02*
X101415Y092705D01*
X101515*
X101565Y092655*
Y092605*
X101515Y092555*
X101465*
X101515*
X101565Y092505*
Y0924551*
X101515Y0924051*
X101415*
X101365Y0924551*
X1304351Y085695D02*
X1303351D01*
X1303851*
Y0854451*
X1303351Y0853951*
X1302851*
X1302351Y0854451*
X130735Y0853951D02*
X130535D01*
X130735Y085595*
Y085645*
X130685Y085695*
X130585*
X130535Y085645*
X12342Y091925D02*
X1233201D01*
X12337*
Y0916751*
X1233201Y0916251*
X1232701*
X1232201Y0916751*
X12352Y0916251D02*
X12362D01*
X12357*
Y091925*
X12352Y091875*
X101345Y0791101D02*
Y0789102D01*
X101495*
Y0790102*
Y0789102*
X1016449*
X101345Y0792101D02*
X1016449D01*
Y0793601*
X1015949Y07941*
X101545*
X101495Y0793601*
Y0792101*
Y0793601*
X101445Y07941*
X101395*
X101345Y0793601*
Y0792101*
X101395Y07951D02*
X101345Y07956D01*
Y0796599*
X101395Y0797099*
X101445*
X101495Y0796599*
Y07961*
Y0796599*
X101545Y0797099*
X1015949*
X1016449Y0796599*
Y07956*
X1015949Y07951*
X104865Y0785801D02*
Y0783802D01*
X105015*
Y0784802*
Y0783802*
X1051649*
X104865Y0786801D02*
X1051649D01*
Y0788301*
X1051149Y07888*
X105065*
X105015Y0788301*
Y0786801*
Y0788301*
X104965Y07888*
X104915*
X104865Y0788301*
Y0786801*
X1051649Y0791799D02*
Y07898D01*
X104965Y0791799*
X104915*
X104865Y0791299*
Y07903*
X104915Y07898*
X092655Y0803651D02*
Y0801652D01*
X092805*
Y0802651*
Y0801652*
X0929549*
X092655Y0804651D02*
X0929549D01*
Y080615*
X0929049Y080665*
X092855*
X092805Y080615*
Y0804651*
Y080615*
X092755Y080665*
X092705*
X092655Y080615*
Y0804651*
X0929549Y080765D02*
Y0808649D01*
Y080815*
X092655*
X092705Y080765*
X12132Y084385D02*
X1211201D01*
Y084235*
X1212201*
X1211201*
Y0840851*
X12142D02*
X12152D01*
X12147*
Y084385*
X12142Y084335*
X06872Y0610499D02*
Y06075D01*
X0688699*
X0689199Y0608*
Y0609999*
X0688699Y0610499*
X06872*
X0690199Y06075D02*
X0691199D01*
X0690699*
Y0610499*
X0690199Y0609999*
X0692698D02*
X0693198Y0610499D01*
X0694198*
X0694698Y0609999*
Y0609499*
X0694198Y0608999*
X0694698Y06085*
Y0608*
X0694198Y06075*
X0693198*
X0692698Y0608*
Y06085*
X0693198Y0608999*
X0692698Y0609499*
Y0609999*
X0693198Y0608999D02*
X0694198D01*
X06872Y0662999D02*
Y066D01*
X0688699*
X0689199Y06605*
Y0662499*
X0688699Y0662999*
X06872*
X0690199Y066D02*
X0691199D01*
X0690699*
Y0662999*
X0690199Y0662499*
X0692698Y0662999D02*
X0694698D01*
Y0662499*
X0692698Y06605*
Y066*
X06872Y0767999D02*
Y0765D01*
X0688699*
X0689199Y07655*
Y0767499*
X0688699Y0767999*
X06872*
X0690199Y0765D02*
X0691199D01*
X0690699*
Y0767999*
X0690199Y0767499*
X0694698Y0767999D02*
X0693698Y0767499D01*
X0692698Y07665*
Y07655*
X0693198Y0765*
X0694198*
X0694698Y07655*
Y0766*
X0694198Y07665*
X0692698*
X06872Y0715499D02*
Y07125D01*
X0688699*
X0689199Y0713*
Y0714999*
X0688699Y0715499*
X06872*
X0690199Y07125D02*
X0691199D01*
X0690699*
Y0715499*
X0690199Y0714999*
X0694698Y0715499D02*
X0692698D01*
Y0714*
X0693698Y0714499*
X0694198*
X0694698Y0714*
Y0713*
X0694198Y07125*
X0693198*
X0692698Y0713*
X071525Y0917177D02*
X0718249D01*
Y0918676*
X0717749Y0919176*
X071575*
X071525Y0918676*
Y0917177*
X0718249Y0920176D02*
Y0921175D01*
Y0920676*
X071525*
X071575Y0920176*
X0718249Y0924175D02*
X071525D01*
X071675Y0922675*
Y0924674*
X069505Y0916877D02*
X0698049D01*
Y0918376*
X0697549Y0918876*
X069555*
X069505Y0918376*
Y0916877*
X0698049Y0919876D02*
Y0920875D01*
Y0920376*
X069505*
X069555Y0919876*
Y0922375D02*
X069505Y0922875D01*
Y0923875*
X069555Y0924374*
X069605*
X069655Y0923875*
Y0923375*
Y0923875*
X069705Y0924374*
X0697549*
X0698049Y0923875*
Y0922875*
X0697549Y0922375*
X067545Y0917277D02*
X0678449D01*
Y0918776*
X0677949Y0919276*
X067595*
X067545Y0918776*
Y0917277*
X0678449Y0920276D02*
Y0921276D01*
Y0920776*
X067545*
X067595Y0920276*
X0678449Y0924774D02*
Y0922775D01*
X067645Y0924774*
X067595*
X067545Y0924275*
Y0923275*
X067595Y0922775*
X065515Y0918227D02*
X0658149D01*
Y0919726*
X0657649Y0920226*
X065565*
X065515Y0919726*
Y0918227*
X0658149Y0921226D02*
Y0922225D01*
Y0921725*
X065515*
X065565Y0921226*
X0658149Y0923725D02*
Y0924724D01*
Y0924225*
X065515*
X065565Y0923725*
X095685Y0857577D02*
X0959849D01*
Y0859076*
X0959349Y0859576*
X095735*
X095685Y0859076*
Y0857577*
X0959849Y0860576D02*
Y0861576D01*
Y0861076*
X095685*
X095735Y0860576*
Y0863075D02*
X095685Y0863575D01*
Y0864575*
X095735Y0865074*
X0959349*
X0959849Y0864575*
Y0863575*
X0959349Y0863075*
X095735*
X095805Y0896551D02*
X0961049D01*
Y0898051*
X0960549Y0898551*
X095855*
X095805Y0898051*
Y0896551*
X0960549Y089955D02*
X0961049Y090005D01*
Y090105*
X0960549Y090155*
X095855*
X095805Y090105*
Y090005*
X095855Y089955*
X095905*
X095955Y090005*
Y090155*
X094535Y0880151D02*
X0948349D01*
Y0881651*
X0947849Y0882151*
X094585*
X094535Y0881651*
Y0880151*
X094585Y088315D02*
X094535Y088365D01*
Y088465*
X094585Y088515*
X094635*
X094685Y088465*
X094735Y088515*
X0947849*
X0948349Y088465*
Y088365*
X0947849Y088315*
X094735*
X094685Y088365*
X094635Y088315*
X094585*
X094685Y088365D02*
Y088465D01*
X092255Y0850451D02*
X0925549D01*
Y0851951*
X0925049Y0852451*
X092305*
X092255Y0851951*
Y0850451*
Y085345D02*
Y085545D01*
X092305*
X0925049Y085345*
X0925549*
X0869551Y088565D02*
Y0882651D01*
X0871051*
X0871551Y0883151*
Y088515*
X0871051Y088565*
X0869551*
X087455D02*
X087355Y088515D01*
X087255Y088415*
Y0883151*
X087305Y0882651*
X087405*
X087455Y0883151*
Y088365*
X087405Y088415*
X087255*
X088555Y0855251D02*
X0888549D01*
Y0856751*
X0888049Y0857251*
X088605*
X088555Y0856751*
Y0855251*
Y086025D02*
Y085825D01*
X088705*
X088655Y085925*
Y085975*
X088705Y086025*
X0888049*
X0888549Y085975*
Y085875*
X0888049Y085825*
X1026751Y086075D02*
Y0857751D01*
X1028251*
X1028751Y0858251*
Y086025*
X1028251Y086075*
X1026751*
X103125Y0857751D02*
Y086075D01*
X102975Y085925*
X103175*
X1233151Y087925D02*
Y0876251D01*
X1234651*
X1235151Y0876751*
Y087875*
X1234651Y087925*
X1233151*
X123615Y087875D02*
X123665Y087925D01*
X123765*
X123815Y087875*
Y087825*
X123765Y087775*
X123715*
X123765*
X123815Y087725*
Y0876751*
X123765Y0876251*
X123665*
X123615Y0876751*
X1219651Y084845D02*
Y0845451D01*
X1221151*
X1221651Y0845951*
Y084795*
X1221151Y084845*
X1219651*
X122465Y0845451D02*
X122265D01*
X122465Y084745*
Y084795*
X122415Y084845*
X122315*
X122265Y084795*
X1206001Y086935D02*
Y0866351D01*
X12075*
X1208Y0866851*
Y086885*
X12075Y086935*
X1206001*
X1209Y0866351D02*
X121D01*
X12095*
Y086935*
X1209Y086885*
X089785Y0779751D02*
X089735Y0779251D01*
Y0778252*
X089785Y0777752*
X0899849*
X0900349Y0778252*
Y0779251*
X0899849Y0779751*
X089735Y0780751D02*
Y078275D01*
X089785*
X0899849Y0780751*
X0900349*
Y078375D02*
Y0784749D01*
Y078425*
X089735*
X089785Y078375*
X0922474Y0818394D02*
X0921974Y0817894D01*
Y0816895*
X0922474Y0816395*
X0924474*
X0924974Y0816895*
Y0817894*
X0924474Y0818394*
X0921974Y0819394D02*
Y0821393D01*
X0922474*
X0924474Y0819394*
X0924974*
X0922474Y0822393D02*
X0921974Y0822893D01*
Y0823892*
X0922474Y0824392*
X0924474*
X0924974Y0823892*
Y0822893*
X0924474Y0822393*
X0922474*
X091245Y0787601D02*
X091195Y0787102D01*
Y0786102*
X091245Y0785602*
X0914449*
X0914949Y0786102*
Y0787102*
X0914449Y0787601*
X091195Y07906D02*
X091245Y0789601D01*
X091345Y0788601*
X0914449*
X0914949Y0789101*
Y07901*
X0914449Y07906*
X091395*
X091345Y07901*
Y0788601*
X0914449Y07916D02*
X0914949Y07921D01*
Y0793099*
X0914449Y0793599*
X091245*
X091195Y0793099*
Y07921*
X091245Y07916*
X091295*
X091345Y07921*
Y0793599*
X090425Y0785901D02*
X090375Y0785401D01*
Y0784402*
X090425Y0783902*
X0906249*
X0906749Y0784402*
Y0785401*
X0906249Y0785901*
X090375Y07889D02*
X090425Y0787901D01*
X090525Y0786901*
X0906249*
X0906749Y0787401*
Y0788401*
X0906249Y07889*
X090575*
X090525Y0788401*
Y0786901*
X090425Y07899D02*
X090375Y07904D01*
Y0791399*
X090425Y0791899*
X090475*
X090525Y0791399*
X090575Y0791899*
X0906249*
X0906749Y0791399*
Y07904*
X0906249Y07899*
X090575*
X090525Y07904*
X090475Y07899*
X090425*
X090525Y07904D02*
Y0791399D01*
X0967599Y0841899D02*
X0967099Y0842399D01*
X09661*
X09656Y0841899*
Y08399*
X09661Y08394*
X0967099*
X0967599Y08399*
X0970598Y0842399D02*
X0969599Y0841899D01*
X0968599Y0840899*
Y08399*
X0969099Y08394*
X0970099*
X0970598Y08399*
Y08404*
X0970099Y0840899*
X0968599*
X0971598Y0842399D02*
X0973597D01*
Y0841899*
X0971598Y08399*
Y08394*
X0979701Y083145D02*
X0979202Y083195D01*
X0978202*
X0977702Y083145*
Y0829451*
X0978202Y0828951*
X0979202*
X0979701Y0829451*
X09827Y083195D02*
X0981701Y083145D01*
X0980701Y083045*
Y0829451*
X0981201Y0828951*
X0982201*
X09827Y0829451*
Y082995*
X0982201Y083045*
X0980701*
X0985699Y083195D02*
X09847Y083145D01*
X09837Y083045*
Y0829451*
X09842Y0828951*
X09852*
X0985699Y0829451*
Y082995*
X09852Y083045*
X09837*
X0976301Y081335D02*
X0975801Y081385D01*
X0974802*
X0974302Y081335*
Y0811351*
X0974802Y0810851*
X0975801*
X0976301Y0811351*
X09793Y081385D02*
X0978301Y081335D01*
X0977301Y081235*
Y0811351*
X0977801Y0810851*
X09788*
X09793Y0811351*
Y081185*
X09788Y081235*
X0977301*
X0982299Y081385D02*
X09803D01*
Y081235*
X09813Y081285*
X09818*
X0982299Y081235*
Y0811351*
X09818Y0810851*
X09808*
X09803Y0811351*
X0905599Y0833599D02*
X0905099Y0834099D01*
X09041*
X09036Y0833599*
Y08316*
X09041Y08311*
X0905099*
X0905599Y08316*
X0908598Y0834099D02*
X0907599Y0833599D01*
X0906599Y08326*
Y08316*
X0907099Y08311*
X0908099*
X0908598Y08316*
Y08321*
X0908099Y08326*
X0906599*
X0911098Y08311D02*
Y0834099D01*
X0909598Y08326*
X0911597*
X0977101Y056425D02*
X0976602Y056475D01*
X0975602*
X0975102Y056425*
Y0562251*
X0975602Y0561751*
X0976602*
X0977101Y0562251*
X09801Y056475D02*
X0979101Y056425D01*
X0978101Y056325*
Y0562251*
X0978601Y0561751*
X0979601*
X09801Y0562251*
Y056275*
X0979601Y056325*
X0978101*
X09811Y056425D02*
X09816Y056475D01*
X09826*
X0983099Y056425*
Y056375*
X09826Y056325*
X09821*
X09826*
X0983099Y056275*
Y0562251*
X09826Y0561751*
X09816*
X09811Y0562251*
X0950501Y057375D02*
X0950002Y057425D01*
X0949002*
X0948502Y057375*
Y0571751*
X0949002Y0571251*
X0950002*
X0950501Y0571751*
X09535Y057425D02*
X0952501Y057375D01*
X0951501Y057275*
Y0571751*
X0952001Y0571251*
X0953001*
X09535Y0571751*
Y057225*
X0953001Y057275*
X0951501*
X0956499Y0571251D02*
X09545D01*
X0956499Y057325*
Y057375*
X0955999Y057425*
X0955*
X09545Y057375*
X087625Y0846651D02*
X087575Y0846151D01*
Y0845152*
X087625Y0844652*
X0878249*
X0878749Y0845152*
Y0846151*
X0878249Y0846651*
X087575Y084965D02*
X087625Y084865D01*
X087725Y0847651*
X0878249*
X0878749Y0848151*
Y084915*
X0878249Y084965*
X087775*
X087725Y084915*
Y0847651*
X0878749Y085065D02*
Y0851649D01*
Y085115*
X087575*
X087625Y085065*
X086875Y0837801D02*
X086825Y0837302D01*
Y0836302*
X086875Y0835802*
X0870749*
X0871249Y0836302*
Y0837302*
X0870749Y0837801*
X086825Y08408D02*
X086875Y0839801D01*
X086975Y0838801*
X0870749*
X0871249Y0839301*
Y08403*
X0870749Y08408*
X087025*
X086975Y08403*
Y0838801*
X086875Y08418D02*
X086825Y08423D01*
Y0843299*
X086875Y0843799*
X0870749*
X0871249Y0843299*
Y08423*
X0870749Y08418*
X086875*
X080615Y0864001D02*
X080565Y0863501D01*
Y0862502*
X080615Y0862002*
X0808149*
X0808649Y0862502*
Y0863501*
X0808149Y0864001*
X080565Y0867D02*
Y0865001D01*
X080715*
X080665Y0866001*
Y08665*
X080715Y0867*
X0808149*
X0808649Y08665*
Y0865501*
X0808149Y0865001*
Y0868D02*
X0808649Y08685D01*
Y0869499*
X0808149Y0869999*
X080615*
X080565Y0869499*
Y08685*
X080615Y0868*
X080665*
X080715Y08685*
Y0869999*
X081975Y0878701D02*
X081925Y0878201D01*
Y0877202*
X081975Y0876702*
X0821749*
X0822249Y0877202*
Y0878201*
X0821749Y0878701*
X081925Y08817D02*
Y0879701D01*
X082075*
X082025Y0880701*
Y0881201*
X082075Y08817*
X0821749*
X0822249Y0881201*
Y0880201*
X0821749Y0879701*
X081975Y08827D02*
X081925Y08832D01*
Y08842*
X081975Y0884699*
X082025*
X082075Y08842*
X082125Y0884699*
X0821749*
X0822249Y08842*
Y08832*
X0821749Y08827*
X082125*
X082075Y08832*
X082025Y08827*
X081975*
X082075Y08832D02*
Y08842D01*
X1258501Y079865D02*
X1258002Y079915D01*
X1257002*
X1256502Y079865*
Y0796651*
X1257002Y0796151*
X1258002*
X1258501Y0796651*
X12615Y079915D02*
X1259501D01*
Y079765*
X1260501Y079815*
X1261001*
X12615Y079765*
Y0796651*
X1261001Y0796151*
X1260001*
X1259501Y0796651*
X12625Y079915D02*
X1264499D01*
Y079865*
X12625Y0796651*
Y0796151*
X1228001Y080725D02*
X1227501Y080775D01*
X1226502*
X1226002Y080725*
Y0805251*
X1226502Y0804751*
X1227501*
X1228001Y0805251*
X1231Y080775D02*
X1229001D01*
Y080625*
X1230001Y080675*
X1230501*
X1231Y080625*
Y0805251*
X1230501Y0804751*
X1229501*
X1229001Y0805251*
X1233999Y080775D02*
X1233Y080725D01*
X1232Y080625*
Y0805251*
X12325Y0804751*
X12335*
X1233999Y0805251*
Y080575*
X12335Y080625*
X1232*
X102635Y0882901D02*
X102585Y0882401D01*
Y0881402*
X102635Y0880902*
X1028349*
X1028849Y0881402*
Y0882401*
X1028349Y0882901*
X102585Y08859D02*
Y0883901D01*
X102735*
X102685Y0884901*
Y08854*
X102735Y08859*
X1028349*
X1028849Y08854*
Y0884401*
X1028349Y0883901*
X102585Y0888899D02*
Y08869D01*
X102735*
X102685Y08879*
Y08884*
X102735Y0888899*
X1028349*
X1028849Y08884*
Y08874*
X1028349Y08869*
X101225Y0891201D02*
X101175Y0890701D01*
Y0889702*
X101225Y0889202*
X1014249*
X1014749Y0889702*
Y0890701*
X1014249Y0891201*
X101175Y08942D02*
Y0892201D01*
X101325*
X101275Y0893201*
Y0893701*
X101325Y08942*
X1014249*
X1014749Y0893701*
Y0892701*
X1014249Y0892201*
X1014749Y08967D02*
X101175D01*
X101325Y08952*
Y0897199*
X1204194Y0744322D02*
X1203694Y0743822D01*
Y0742823*
X1204194Y0742323*
X1206193*
X1206693Y0742823*
Y0743822*
X1206193Y0744322*
X1206693Y0747321D02*
Y0745322D01*
X1204694Y0747321*
X1204194*
X1203694Y0746821*
Y0745822*
X1204194Y0745322*
X1206693Y075032D02*
Y0748321D01*
X1204694Y075032*
X1204194*
X1203694Y074982*
Y0748821*
X1204194Y0748321*
X1209184Y0711751D02*
X1208685Y0712251D01*
X1207685*
X1207185Y0711751*
Y0709752*
X1207685Y0709252*
X1208685*
X1209184Y0709752*
X1212183Y0709252D02*
X1210184D01*
X1212183Y0711251*
Y0711751*
X1211684Y0712251*
X1210684*
X1210184Y0711751*
X1213183Y0709252D02*
X1214183D01*
X1213683*
Y0712251*
X1213183Y0711751*
X1291497Y0698259D02*
X1290997Y0697759D01*
Y069676*
X1291497Y069626*
X1293496*
X1293996Y069676*
Y0697759*
X1293496Y0698259*
X1293996Y0701258D02*
Y0699259D01*
X1291997Y0701258*
X1291497*
X1290997Y0700758*
Y0699759*
X1291497Y0699259*
Y0702258D02*
X1290997Y0702758D01*
Y0703757*
X1291497Y0704257*
X1293496*
X1293996Y0703757*
Y0702758*
X1293496Y0702258*
X1291497*
X1284381Y0717361D02*
X1283881Y0717861D01*
X1282882*
X1282382Y0717361*
Y0715362*
X1282882Y0714862*
X1283881*
X1284381Y0715362*
X1285381Y0714862D02*
X1286381D01*
X1285881*
Y0717861*
X1285381Y0717361*
X128788Y0715362D02*
X128838Y0714862D01*
X128938*
X128988Y0715362*
Y0717361*
X128938Y0717861*
X128838*
X128788Y0717361*
Y0716861*
X128838Y0716362*
X128988*
X1271776Y067625D02*
X1271276Y067675D01*
X1270277*
X1269777Y067625*
Y0674251*
X1270277Y0673751*
X1271276*
X1271776Y0674251*
X1272776Y0673751D02*
X1273775D01*
X1273276*
Y067675*
X1272776Y067625*
X1275275D02*
X1275775Y067675D01*
X1276775*
X1277274Y067625*
Y067575*
X1276775Y067525*
X1277274Y067475*
Y0674251*
X1276775Y0673751*
X1275775*
X1275275Y0674251*
Y067475*
X1275775Y067525*
X1275275Y067575*
Y067625*
X1275775Y067525D02*
X1276775D01*
X1271876Y066975D02*
X1271376Y067025D01*
X1270377*
X1269877Y066975*
Y0667751*
X1270377Y0667251*
X1271376*
X1271876Y0667751*
X1272876Y0667251D02*
X1273876D01*
X1273376*
Y067025*
X1272876Y066975*
X1275375Y067025D02*
X1277374D01*
Y066975*
X1275375Y0667751*
Y0667251*
X1271776Y066325D02*
X1271276Y066375D01*
X1270277*
X1269777Y066325*
Y0661251*
X1270277Y0660751*
X1271276*
X1271776Y0661251*
X1272776Y0660751D02*
X1273775D01*
X1273276*
Y066375*
X1272776Y066325*
X1277274Y066375D02*
X1276275Y066325D01*
X1275275Y066225*
Y0661251*
X1275775Y0660751*
X1276775*
X1277274Y0661251*
Y066175*
X1276775Y066225*
X1275275*
X1275176Y065665D02*
X1274676Y065715D01*
X1273677*
X1273177Y065665*
Y0654651*
X1273677Y0654151*
X1274676*
X1275176Y0654651*
X1276176Y0654151D02*
X1277176D01*
X1276676*
Y065715*
X1276176Y065665*
X1280674Y065715D02*
X1278675D01*
Y065565*
X1279675Y065615*
X1280175*
X1280674Y065565*
Y0654651*
X1280175Y0654151*
X1279175*
X1278675Y0654651*
X1275276Y065005D02*
X1274776Y065055D01*
X1273777*
X1273277Y065005*
Y0648051*
X1273777Y0647551*
X1274776*
X1275276Y0648051*
X1276276Y0647551D02*
X1277275D01*
X1276776*
Y065055*
X1276276Y065005*
X1280275Y0647551D02*
Y065055D01*
X1278775Y064905*
X1280774*
X1275176Y064265D02*
X1274676Y064315D01*
X1273677*
X1273177Y064265*
Y0640651*
X1273677Y0640151*
X1274676*
X1275176Y0640651*
X1276176Y0640151D02*
X1277176D01*
X1276676*
Y064315*
X1276176Y064265*
X1278675D02*
X1279175Y064315D01*
X1280175*
X1280674Y064265*
Y064215*
X1280175Y064165*
X1279675*
X1280175*
X1280674Y064115*
Y0640651*
X1280175Y0640151*
X1279175*
X1278675Y0640651*
X1218929Y0765491D02*
X1218429Y0765991D01*
X1217429*
X1216929Y0765491*
Y0763492*
X1217429Y0762992*
X1218429*
X1218929Y0763492*
X1219928Y0762992D02*
X1220928D01*
X1220428*
Y0765991*
X1219928Y0765491*
X1224427Y0762992D02*
X1222427D01*
X1224427Y0764992*
Y0765491*
X1223927Y0765991*
X1222927*
X1222427Y0765491*
X121883Y076057D02*
X121833Y076107D01*
X1217331*
X1216831Y076057*
Y0758571*
X1217331Y0758071*
X121833*
X121883Y0758571*
X121983Y0758071D02*
X1220829D01*
X122033*
Y076107*
X121983Y076057*
X1222329Y0758071D02*
X1223329D01*
X1222829*
Y076107*
X1222329Y076057*
X1218732Y0755649D02*
X1218232Y0756149D01*
X1217232*
X1216732Y0755649*
Y0753649*
X1217232Y075315*
X1218232*
X1218732Y0753649*
X1219731Y075315D02*
X1220731D01*
X1220231*
Y0756149*
X1219731Y0755649*
X1222231D02*
X122273Y0756149D01*
X122373*
X122423Y0755649*
Y0753649*
X122373Y075315*
X122273*
X1222231Y0753649*
Y0755649*
X1218929Y0770609D02*
X1218429Y0771109D01*
X1217429*
X1216929Y0770609*
Y076861*
X1217429Y076811*
X1218429*
X1218929Y076861*
X1219928D02*
X1220428Y076811D01*
X1221428*
X1221928Y076861*
Y0770609*
X1221428Y0771109*
X1220428*
X1219928Y0770609*
Y077011*
X1220428Y076961*
X1221928*
X1230276Y0790484D02*
X1229777Y0789984D01*
Y0788984*
X1230276Y0788484*
X1232276*
X1232776Y0788984*
Y0789984*
X1232276Y0790484*
X1230276Y0791483D02*
X1229777Y0791983D01*
Y0792983*
X1230276Y0793483*
X1230776*
X1231276Y0792983*
X1231776Y0793483*
X1232276*
X1232776Y0792983*
Y0791983*
X1232276Y0791483*
X1231776*
X1231276Y0791983*
X1230776Y0791483*
X1230276*
X1231276Y0791983D02*
Y0792983D01*
X1216989Y0790779D02*
X1216489Y0790279D01*
Y0789279*
X1216989Y0788779*
X1218988*
X1219488Y0789279*
Y0790279*
X1218988Y0790779*
X1216489Y0791779D02*
Y0793778D01*
X1216989*
X1218988Y0791779*
X1219488*
X1264036Y0723555D02*
X1263536Y0723055D01*
Y0722055*
X1264036Y0721555*
X1266036*
X1266535Y0722055*
Y0723055*
X1266036Y0723555*
X1263536Y0726553D02*
X1264036Y0725554D01*
X1265036Y0724554*
X1266036*
X1266535Y0725054*
Y0726054*
X1266036Y0726553*
X1265536*
X1265036Y0726054*
Y0724554*
X1231625Y0706141D02*
X1231126Y0706641D01*
X1230126*
X1229626Y0706141*
Y0704142*
X1230126Y0703642*
X1231126*
X1231625Y0704142*
X1234624Y0706641D02*
X1232625D01*
Y0705141*
X1233625Y0705641*
X1234124*
X1234624Y0705141*
Y0704142*
X1234124Y0703642*
X1233125*
X1232625Y0704142*
X1249568Y0708988D02*
X1249068Y0708488D01*
Y0707488*
X1249568Y0706988*
X1251567*
X1252067Y0707488*
Y0708488*
X1251567Y0708988*
X1252067Y0711487D02*
X1249068D01*
X1250567Y0709987*
Y0711987*
X1245139Y0717058D02*
X1244639Y0716559D01*
Y0715559*
X1245139Y0715059*
X1247138*
X1247638Y0715559*
Y0716559*
X1247138Y0717058*
X1245139Y0718058D02*
X1244639Y0718558D01*
Y0719558*
X1245139Y0720057*
X1245638*
X1246138Y0719558*
Y0719058*
Y0719558*
X1246638Y0720057*
X1247138*
X1247638Y0719558*
Y0718558*
X1247138Y0718058*
X1162151Y084275D02*
X1161651Y084325D01*
X1160651*
X1160151Y084275*
Y0840751*
X1160651Y0840251*
X1161651*
X1162151Y0840751*
X116515Y0840251D02*
X116315D01*
X116515Y084225*
Y084275*
X116465Y084325*
X116365*
X116315Y084275*
X11763Y084295D02*
X1175801Y084345D01*
X1174801*
X1174301Y084295*
Y0840951*
X1174801Y0840451*
X1175801*
X11763Y0840951*
X11773Y0840451D02*
X11783D01*
X11778*
Y084345*
X11773Y084295*
X06527Y06066D02*
Y0608599D01*
X06537Y0609599*
X0654699Y0608599*
Y06066*
Y06081*
X06527*
X0655699Y06066D02*
Y0609599D01*
X0657698Y06066*
Y0609599*
X0658698Y0609099D02*
X0659198Y0609599D01*
X0660198*
X0660697Y0609099*
Y0608599*
X0660198Y06081*
X0660697Y06076*
Y06071*
X0660198Y06066*
X0659198*
X0658698Y06071*
Y06076*
X0659198Y06081*
X0658698Y0608599*
Y0609099*
X0659198Y06081D02*
X0660198D01*
X06527Y06591D02*
Y0661099D01*
X06537Y0662099*
X0654699Y0661099*
Y06591*
Y06606*
X06527*
X0655699Y06591D02*
Y0662099D01*
X0657698Y06591*
Y0662099*
X0658698D02*
X0660697D01*
Y0661599*
X0658698Y06596*
Y06591*
X06527Y07641D02*
Y0766099D01*
X06537Y0767099*
X0654699Y0766099*
Y07641*
Y0765599*
X06527*
X0655699Y07641D02*
Y0767099D01*
X0657698Y07641*
Y0767099*
X0660697D02*
X0659698Y0766599D01*
X0658698Y0765599*
Y07646*
X0659198Y07641*
X0660198*
X0660697Y07646*
Y07651*
X0660198Y0765599*
X0658698*
X06527Y07116D02*
Y0713599D01*
X06537Y0714599*
X0654699Y0713599*
Y07116*
Y0713099*
X06527*
X0655699Y07116D02*
Y0714599D01*
X0657698Y07116*
Y0714599*
X0660697D02*
X0658698D01*
Y0713099*
X0659698Y0713599*
X0660198*
X0660697Y0713099*
Y07121*
X0660198Y07116*
X0659198*
X0658698Y07121*
X0639502Y0573251D02*
Y057525D01*
X0640502Y057625*
X0641501Y057525*
Y0573251*
Y057475*
X0639502*
X0642501Y0573251D02*
Y057625D01*
X06445Y0573251*
Y057625*
X0647Y0573251D02*
Y057625D01*
X06455Y057475*
X0647499*
X0639702Y0625651D02*
Y062765D01*
X0640702Y062865*
X0641701Y062765*
Y0625651*
Y062715*
X0639702*
X0642701Y0625651D02*
Y062865D01*
X06447Y0625651*
Y062865*
X06457Y062815D02*
X06462Y062865D01*
X0647199*
X0647699Y062815*
Y062765*
X0647199Y062715*
X06467*
X0647199*
X0647699Y062665*
Y0626151*
X0647199Y0625651*
X06462*
X06457Y0626151*
X0639502Y0677951D02*
Y067995D01*
X0640502Y068095*
X0641501Y067995*
Y0677951*
Y067945*
X0639502*
X0642501Y0677951D02*
Y068095D01*
X06445Y0677951*
Y068095*
X0647499Y0677951D02*
X06455D01*
X0647499Y067995*
Y068045*
X0647Y068095*
X0646*
X06455Y068045*
X0639652Y0730551D02*
Y073255D01*
X0640651Y073355*
X0641651Y073255*
Y0730551*
Y073205*
X0639652*
X0642651Y0730551D02*
Y073355D01*
X064465Y0730551*
Y073355*
X064565Y0730551D02*
X0646649D01*
X064615*
Y073355*
X064565Y073305*
X1063451Y089265D02*
Y0890151D01*
X1063951Y0889651*
X1064951*
X1065451Y0890151*
Y089265*
X106645D02*
X106845D01*
Y089215*
X106645Y0890151*
Y0889651*
G54D25*
X125475Y08155D03*
M02*